G04 ================== begin FILE IDENTIFICATION RECORD ==================*
G04 Layout Name:  9048_F0T_Management_Board_D_brd_V04_1213_1625.brd*
G04 Film Name:    ssb*
G04 File Format:  Gerber RS274X*
G04 File Origin:  Cadence Allegro 17.2-S081*
G04 Origin Date:  Tue Dec 13 16:31:11 2022*
G04 *
G04 Layer:  DRAWING FORMAT/TITLE_BLOCK_A*
G04 Layer:  BOARD GEOMETRY/DESIGN_OUTLINE*
G04 Layer:  BOARD GEOMETRY/CUTOUT*
G04 Layer:  BOARD GEOMETRY/OUTLINE*
G04 Layer:  DRAWING FORMAT/TITLE_BLOCK*
G04 Layer:  MANUFACTURING/TP_TEXT_BOTTOM*
G04 Layer:  REF DES/SILKSCREEN_BOTTOM*
G04 Layer:  PACKAGE GEOMETRY/SILKSCREEN_BOTTOM*
G04 Layer:  MANUFACTURING/PHOTOPLOT_OUTLINE*
G04 Layer:  DRAWING FORMAT/TITLE_DATA_SSB*
G04 Layer:  BOARD GEOMETRY/SILKSCREEN_BOTTOM*
G04 *
G04 Offset:    (0.00 0.00)*
G04 Mirror:    No*
G04 Mode:      Positive*
G04 Rotation:  0*
G04 FullContactRelief:  No*
G04 UndefLineWidth:     6.00*
G04 ================== end FILE IDENTIFICATION RECORD ====================*
%FSLAX25Y25*MOIN*%
%IR0*IPPOS*OFA0.00000B0.00000*MIA0B0*SFA1.00000B1.00000*%
%ADD10C,.01*%
%ADD11C,.006*%
G75*
%LPD*%
G75*
G36*
G01X45778Y174682D02*
X46278Y175232D01*
X42143Y179530D01*
X42632Y184960D01*
X46478Y188932D01*
X46228Y189632D01*
X45528Y189732D01*
X42807Y186904D01*
X42915Y188100D01*
X41675Y189100D01*
X40675Y189150D01*
X39725Y189600D01*
X37575D01*
X37025Y189350D01*
X35875Y188500D01*
X35675D01*
X35275Y188900D01*
X34475Y188800D01*
X34125Y188400D01*
Y187864D01*
X32328Y189732D01*
X31628Y189632D01*
X31378Y188932D01*
X34125Y186095D01*
Y185050D01*
X34375Y184750D01*
X34975D01*
X35571Y179383D01*
X35477Y179285D01*
X35425Y179250D01*
G03X34802Y178583I1089J-1641D01*
G01X31578Y175232D01*
X32078Y174682D01*
X32728Y174732D01*
X34722Y176791D01*
G03X38175Y176550I1792J818D01*
G01X41875D01*
X42002Y177960D01*
X45128Y174732D01*
X45778Y174682D01*
G37*
G36*
G01X45500Y174300D02*
X32350D01*
Y172000D01*
X45500D01*
Y174300D01*
G37*
G36*
G01X39050Y112626D02*
X37315Y111759D01*
X39050Y110892D01*
Y112626D01*
G37*
G36*
G01X61054Y90948D02*
X65054Y92948D01*
Y88948D01*
X61054Y90948D01*
G37*
G36*
G01X69500Y244000D02*
X68000Y241000D01*
X71000D01*
X69500Y244000D01*
G37*
G36*
G01X78646Y312884D02*
X80060Y317127D01*
X82889Y314298D01*
X78646Y312884D01*
G37*
G36*
G01X118613Y137693D02*
Y139193D01*
X125699D01*
Y137693D01*
X118613D01*
G37*
G36*
G01X109457Y137850D02*
Y139350D01*
X116543D01*
Y137850D01*
X109457D01*
G37*
G36*
G01X123559Y253800D02*
X122059Y250800D01*
X125059D01*
X123559Y253800D01*
G37*
G36*
G01X124610Y394124D02*
X128610D01*
X126610Y390124D01*
X124610Y394124D01*
G37*
G36*
G01X139062Y256522D02*
X140122Y253340D01*
X142244Y255461D01*
X139062Y256522D01*
G37*
G36*
G01X153894Y10503D02*
X152703Y8121D01*
X155085D01*
X153894Y10503D01*
G37*
G36*
G01X174394D02*
X173203Y8121D01*
X175585D01*
X174394Y10503D01*
G37*
G36*
G01X179230Y73679D02*
X177230D01*
X178230Y75679D01*
X179230Y73679D01*
G37*
G36*
G01X177107Y305847D02*
X173107Y303847D01*
Y307847D01*
X177107Y305847D01*
G37*
G36*
G01X173019Y363185D02*
X175401Y361994D01*
Y364376D01*
X173019Y363185D01*
G37*
G36*
G01X187968Y409462D02*
X191968Y411462D01*
Y407462D01*
X187968Y409462D01*
G37*
G36*
G01X233494Y77303D02*
X232303Y74921D01*
X234685D01*
X233494Y77303D01*
G37*
G36*
G01X240711Y368620D02*
X242211Y371620D01*
X239211D01*
X240711Y368620D01*
G37*
G36*
G01X247994Y77303D02*
X246803Y74921D01*
X249185D01*
X247994Y77303D01*
G37*
G36*
G01X253500Y378000D02*
X249500Y376000D01*
Y380000D01*
X253500Y378000D01*
G37*
G36*
G01X318898Y108517D02*
X316070Y105689D01*
X314655Y109931D01*
X318898Y108517D01*
G37*
G36*
G01X311441Y277450D02*
X312341Y279750D01*
X310641D01*
X311441Y277450D01*
G37*
G36*
G01X441000Y-212001D02*
X438000Y-206001D01*
X444000D01*
X441000Y-212001D01*
G37*
G36*
G01X451000Y-139599D02*
X454000Y-145599D01*
X448000D01*
X451000Y-139599D01*
G37*
G36*
G01X441000Y-104001D02*
X438000Y-98001D01*
X444000D01*
X441000Y-104001D01*
G37*
G36*
G01X451000Y-20999D02*
X454000Y-26999D01*
X448000D01*
X451000Y-20999D01*
G37*
G36*
G01X441000Y232999D02*
X438000Y238999D01*
X444000D01*
X441000Y232999D01*
G37*
G36*
G01X451000Y301001D02*
X454000Y295001D01*
X448000D01*
X451000Y301001D01*
G37*
G36*
G01X441000Y338999D02*
X438000Y344999D01*
X444000D01*
X441000Y338999D01*
G37*
G36*
G01X451000Y417001D02*
X454000Y411001D01*
X448000D01*
X451000Y417001D01*
G37*
%LPC*%
G75*
G36*
G01X38928Y182872D02*
X41294Y185331D01*
X41375Y186600D01*
X36475D01*
X36554Y185340D01*
X38928Y182872D01*
G37*
G36*
G01X39766Y182001D02*
X40999Y180719D01*
X41174Y183454D01*
X39766Y182001D01*
G37*
G36*
G01X36843Y180705D02*
X38090Y182001D01*
X36671Y183466D01*
X36843Y180705D01*
G37*
G36*
G01X37175Y179300D02*
G02X38475Y177950I-849J-2119D01*
G01X40825Y178000D01*
X40896Y179103D01*
X38928Y181135D01*
X37158Y179307D01*
X37175Y179300D01*
G37*
%LPD*%
G75*
G36*
G01X40275Y185550D02*
X37575D01*
Y184800D01*
X40275D01*
Y185550D01*
G37*
G54D10*
G01X331800Y249400D02*
X330700Y250000D01*
Y245000D01*
G01X332910Y263800D02*
G03I-2410J0D01*
G01X338300Y247700D02*
X333100D01*
X333200Y248400D01*
X333300Y248700D01*
X333500Y249100D01*
X333800Y249500D01*
X334300Y249900D01*
X334700Y250100D01*
X335000Y250200D01*
X335500Y250300D01*
X335900D01*
X336400Y250200D01*
X336700Y250100D01*
X337100Y249900D01*
X337500Y249600D01*
X337600Y249500D01*
X337900Y249100D01*
X338100Y248700D01*
X338200Y248400D01*
X338300Y247800D01*
Y247500D01*
X338200Y247000D01*
X338100Y246700D01*
X337900Y246300D01*
X337600Y245900D01*
X337100Y245500D01*
X336700Y245300D01*
X336400Y245200D01*
X335800Y245100D01*
X335700D01*
X335000Y245200D01*
X334700Y245300D01*
X334500Y245400D01*
X333900Y245800D01*
X333500Y246300D01*
G01X339000Y271500D02*
Y261400D01*
G01Y271500D02*
X336500D01*
G03Y266500I0J-2500D01*
G01X339000D01*
G01X332900Y271500D02*
Y261400D01*
G54D11*
G01X2010999Y-388000D02*
Y1475775D01*
X-407000D01*
Y-386798D01*
Y-755294D01*
Y-793716D01*
X-368578D01*
X1942346D01*
X2010999D01*
Y-725063D01*
Y-388000D01*
G01X-53307Y-609436D02*
Y-684436D01*
X446693D01*
Y-609436D01*
X-53307D01*
G01X-41307Y-674436D02*
Y-679436D01*
G01X-42764Y-674436D02*
X-39850D01*
G01X-34940Y-679436D02*
X-37474D01*
Y-674436D01*
X-34940D01*
G01X-35954Y-676853D02*
X-37474D01*
G01X-32374Y-674436D02*
Y-679436D01*
X-29840D01*
G01X-26007Y-679603D02*
X-26134Y-679519D01*
Y-679353D01*
X-26007Y-679269D01*
X-25880Y-679353D01*
Y-679519D01*
X-26007Y-679603D01*
G01Y-677353D02*
X-26134Y-677269D01*
Y-677103D01*
X-26007Y-677019D01*
X-25880Y-677103D01*
Y-677269D01*
X-26007Y-677353D01*
G01X-21224Y-681103D02*
X-21857Y-680269D01*
X-22174Y-679436D01*
Y-676103D01*
X-21857Y-675269D01*
X-21224Y-674436D01*
G01X-15807D02*
X-16314Y-674603D01*
X-16694Y-675019D01*
X-16947Y-675519D01*
X-17137Y-676186D01*
X-17200Y-676936D01*
X-17137Y-677686D01*
X-16947Y-678353D01*
X-16694Y-678853D01*
X-16314Y-679269D01*
X-15807Y-679436D01*
X-15300Y-679269D01*
X-14920Y-678853D01*
X-14667Y-678353D01*
X-14477Y-677686D01*
X-14414Y-676936D01*
X-14477Y-676186D01*
X-14667Y-675519D01*
X-14920Y-675019D01*
X-15300Y-674603D01*
X-15807Y-674436D01*
G01X-12100Y-678436D02*
X-11720Y-679019D01*
X-11214Y-679353D01*
X-10644Y-679436D01*
X-10137Y-679353D01*
X-9630Y-678936D01*
X-9314Y-678436D01*
X-9250Y-677936D01*
X-9377Y-677353D01*
X-9820Y-676936D01*
X-10264Y-676769D01*
X-10834D01*
G01X-10264D02*
X-9884Y-676519D01*
X-9567Y-676103D01*
X-9440Y-675603D01*
X-9567Y-675103D01*
X-9884Y-674686D01*
X-10454Y-674436D01*
X-11024Y-674519D01*
X-11594Y-674853D01*
G01X-5290Y-681103D02*
X-4657Y-680269D01*
X-4340Y-679436D01*
Y-676103D01*
X-4657Y-675269D01*
X-5290Y-674436D01*
G01X-1900Y-678436D02*
X-1520Y-679019D01*
X-1014Y-679353D01*
X-444Y-679436D01*
X63Y-679353D01*
X570Y-678936D01*
X886Y-678436D01*
X950Y-677936D01*
X823Y-677353D01*
X380Y-676936D01*
X-64Y-676769D01*
X-634D01*
G01X-64D02*
X316Y-676519D01*
X633Y-676103D01*
X760Y-675603D01*
X633Y-675103D01*
X316Y-674686D01*
X-254Y-674436D01*
X-824Y-674519D01*
X-1394Y-674853D01*
G01X3390Y-675269D02*
X3770Y-674769D01*
X4213Y-674519D01*
X4720Y-674436D01*
X5353Y-674603D01*
X5796Y-675019D01*
X5923Y-675519D01*
X5860Y-676019D01*
X5606Y-676436D01*
X4340Y-677269D01*
X3770Y-677853D01*
X3390Y-678686D01*
X3263Y-679436D01*
X5923D01*
G01X9566D02*
X9693Y-678353D01*
X9883Y-677436D01*
X10136Y-676603D01*
X10453Y-675686D01*
X10960Y-674436D01*
X8426D01*
G01X13970Y-677769D02*
X15616D01*
G01X18690Y-675269D02*
X19070Y-674769D01*
X19513Y-674519D01*
X20020Y-674436D01*
X20653Y-674603D01*
X21096Y-675019D01*
X21223Y-675519D01*
X21160Y-676019D01*
X20906Y-676436D01*
X19640Y-677269D01*
X19070Y-677853D01*
X18690Y-678686D01*
X18563Y-679436D01*
X21223D01*
G01X23600Y-678436D02*
X23980Y-679019D01*
X24486Y-679353D01*
X25056Y-679436D01*
X25563Y-679353D01*
X26070Y-678936D01*
X26386Y-678436D01*
X26450Y-677936D01*
X26323Y-677353D01*
X25880Y-676936D01*
X25436Y-676769D01*
X24866D01*
G01X25436D02*
X25816Y-676519D01*
X26133Y-676103D01*
X26260Y-675603D01*
X26133Y-675103D01*
X25816Y-674686D01*
X25246Y-674436D01*
X24676Y-674519D01*
X24106Y-674853D01*
G01X30853Y-679436D02*
Y-674436D01*
X28510Y-678019D01*
X31676D01*
G01X33800Y-678686D02*
X34180Y-679103D01*
X34623Y-679353D01*
X35193Y-679436D01*
X35763Y-679269D01*
X36206Y-678936D01*
X36523Y-678353D01*
X36586Y-677686D01*
X36460Y-677019D01*
X36143Y-676603D01*
X35700Y-676269D01*
X35256Y-676186D01*
X34813Y-676269D01*
X34243Y-676603D01*
X34433Y-674436D01*
X36143D01*
G01X44190Y-679436D02*
Y-674436D01*
X46596D01*
G01X45710Y-676853D02*
X44190D01*
G01X48910Y-679436D02*
X50493Y-674436D01*
X52076Y-679436D01*
G01X51506Y-677686D02*
X49480D01*
G01X54263Y-679436D02*
X56923Y-674436D01*
G01X54263D02*
X56923Y-679436D01*
G01X60693Y-679603D02*
X60566Y-679519D01*
Y-679353D01*
X60693Y-679269D01*
X60820Y-679353D01*
Y-679519D01*
X60693Y-679603D01*
G01Y-677353D02*
X60566Y-677269D01*
Y-677103D01*
X60693Y-677019D01*
X60820Y-677103D01*
Y-677269D01*
X60693Y-677353D01*
G01X65476Y-681103D02*
X64843Y-680269D01*
X64526Y-679436D01*
Y-676103D01*
X64843Y-675269D01*
X65476Y-674436D01*
G01X70893D02*
X70386Y-674603D01*
X70006Y-675019D01*
X69753Y-675519D01*
X69563Y-676186D01*
X69500Y-676936D01*
X69563Y-677686D01*
X69753Y-678353D01*
X70006Y-678853D01*
X70386Y-679269D01*
X70893Y-679436D01*
X71400Y-679269D01*
X71780Y-678853D01*
X72033Y-678353D01*
X72223Y-677686D01*
X72286Y-676936D01*
X72223Y-676186D01*
X72033Y-675519D01*
X71780Y-675019D01*
X71400Y-674603D01*
X70893Y-674436D01*
G01X74600Y-678436D02*
X74980Y-679019D01*
X75486Y-679353D01*
X76056Y-679436D01*
X76563Y-679353D01*
X77070Y-678936D01*
X77386Y-678436D01*
X77450Y-677936D01*
X77323Y-677353D01*
X76880Y-676936D01*
X76436Y-676769D01*
X75866D01*
G01X76436D02*
X76816Y-676519D01*
X77133Y-676103D01*
X77260Y-675603D01*
X77133Y-675103D01*
X76816Y-674686D01*
X76246Y-674436D01*
X75676Y-674519D01*
X75106Y-674853D01*
G01X81410Y-681103D02*
X82043Y-680269D01*
X82360Y-679436D01*
Y-676103D01*
X82043Y-675269D01*
X81410Y-674436D01*
G01X84800Y-678436D02*
X85180Y-679019D01*
X85686Y-679353D01*
X86256Y-679436D01*
X86763Y-679353D01*
X87270Y-678936D01*
X87586Y-678436D01*
X87650Y-677936D01*
X87523Y-677353D01*
X87080Y-676936D01*
X86636Y-676769D01*
X86066D01*
G01X86636D02*
X87016Y-676519D01*
X87333Y-676103D01*
X87460Y-675603D01*
X87333Y-675103D01*
X87016Y-674686D01*
X86446Y-674436D01*
X85876Y-674519D01*
X85306Y-674853D01*
G01X90216Y-678853D02*
X90660Y-679269D01*
X91166Y-679436D01*
X91673Y-679269D01*
X92116Y-678769D01*
X92433Y-678019D01*
X92560Y-677269D01*
Y-676353D01*
X92433Y-675603D01*
X92116Y-674936D01*
X91736Y-674603D01*
X91293Y-674436D01*
X90786Y-674603D01*
X90406Y-674936D01*
X90153Y-675436D01*
X90026Y-676103D01*
X90153Y-676686D01*
X90470Y-677269D01*
X90850Y-677603D01*
X91293Y-677686D01*
X91800Y-677519D01*
X92180Y-677103D01*
X92560Y-676353D01*
G01X96266Y-679436D02*
X96393Y-678353D01*
X96583Y-677436D01*
X96836Y-676603D01*
X97153Y-675686D01*
X97660Y-674436D01*
X95126D01*
G01X100670Y-677769D02*
X102316D01*
G01X105200Y-678436D02*
X105580Y-679019D01*
X106086Y-679353D01*
X106656Y-679436D01*
X107163Y-679353D01*
X107670Y-678936D01*
X107986Y-678436D01*
X108050Y-677936D01*
X107923Y-677353D01*
X107480Y-676936D01*
X107036Y-676769D01*
X106466D01*
G01X107036D02*
X107416Y-676519D01*
X107733Y-676103D01*
X107860Y-675603D01*
X107733Y-675103D01*
X107416Y-674686D01*
X106846Y-674436D01*
X106276Y-674519D01*
X105706Y-674853D01*
G01X110490Y-677353D02*
X110933Y-676769D01*
X111313Y-676436D01*
X111820Y-676269D01*
X112263Y-676436D01*
X112580Y-676769D01*
X112833Y-677269D01*
X112896Y-677853D01*
X112833Y-678353D01*
X112580Y-678853D01*
X112200Y-679269D01*
X111756Y-679436D01*
X111250Y-679269D01*
X110806Y-678769D01*
X110553Y-678019D01*
X110490Y-677186D01*
X110616Y-676103D01*
X110806Y-675519D01*
X111123Y-674936D01*
X111566Y-674519D01*
X112010Y-674436D01*
X112453Y-674603D01*
X112770Y-675019D01*
G01X116793Y-679436D02*
Y-674436D01*
X116033Y-675436D01*
G01Y-679436D02*
X117553D01*
G01X122653D02*
Y-674436D01*
X120310Y-678019D01*
X123476D01*
G01X7874Y450000D02*
G03X0Y442126I0J-7874D01*
G01Y335630D01*
G03X984Y334646I984J0D01*
G01X8858D01*
G02X10827Y332677I0J-1969D01*
G01Y322835D01*
G02X8858Y320866I-1969J0D01*
G01X984D01*
G03X0Y319882I0J-984D01*
G01Y7874D01*
G03X7874Y0I7874J0D01*
G01X346457D01*
G03X354331Y7874I0J7874D01*
G01Y319882D01*
G03X353346Y320866I-984J0D01*
G01X345472D01*
G02X343504Y322835I0J1968D01*
G01Y332677D01*
G02X345472Y334646I1968J0D01*
G01X353346D01*
G03X354331Y335630I1J984D01*
G01Y442126D01*
G03X346457Y450000I-7874J0D01*
G01X336614D01*
G02X334646Y451969I0J1969D01*
G01Y469024D01*
X331764Y474016D01*
X314921D01*
X311969Y471063D01*
Y451969D01*
G02X310000Y450000I-1969J0D01*
G01X304094D01*
G02X302126Y451969I1J1969D01*
G01Y471063D01*
X299173Y474016D01*
X265886D01*
X262933Y471063D01*
Y450886D01*
G02X254075I-4429J0D01*
G01Y471063D01*
X251122Y474016D01*
X184783D01*
X181831Y471063D01*
Y450098D01*
G02X174547I-3642J0D01*
G01Y471063D01*
X171594Y474016D01*
X138287D01*
X135335Y471063D01*
Y451870D01*
G02X124508I-5413J0D01*
G01Y471063D01*
X121555Y474016D01*
X55177D01*
X52224Y471063D01*
Y451969D01*
G02X50256Y450000I-1969J0D01*
G01X44350D01*
G02X42382Y451969I0J1969D01*
G01Y471063D01*
X39429Y474016D01*
X22567D01*
X19685Y469024D01*
Y451969D01*
G02X17717Y450000I-1969J0D01*
G01X7874D01*
G01X28346Y46417D02*
G02X15748I-6299J0D01*
G02X28346I6299J0D01*
G01X15748D02*
G02X28346I6299J0D01*
G02X15748I-6299J0D01*
G01D02*
G02X28346I6299J0D01*
G02X15748I-6299J0D01*
G01X30177Y89331D02*
G02X17854I-6161J0D01*
G02X30177I6162J0D01*
G01X17854D02*
G02X30177I6162J0D01*
G02X17854I-6161J0D01*
G01D02*
G02X30177I6162J0D01*
G02X17854I-6161J0D01*
G01X6447Y140976D02*
X6364Y141056D01*
G01X6684Y140976D02*
X6315Y141330D01*
G01X6921Y140976D02*
X6267Y141604D01*
G01X7157Y140976D02*
X6220Y141876D01*
G01X7395Y140976D02*
X6173Y142148D01*
G01X7632Y140976D02*
X6124Y142422D01*
G01X7869Y140976D02*
X6076Y142696D01*
G01X8105Y140976D02*
X6029Y142968D01*
G01X8341Y140976D02*
X5980Y143241D01*
G01X8579Y140976D02*
X5932Y143515D01*
G01X8816Y140976D02*
X5885Y143789D01*
G01X9053Y140976D02*
X5836Y144061D01*
G01X9289Y140976D02*
X5789Y144334D01*
G01X9527Y140976D02*
X5741Y144607D01*
G01X9764Y140976D02*
X5692Y144881D01*
G01X10000Y140976D02*
X5645Y145153D01*
G01X10236Y140976D02*
X5597Y145426D01*
G01X10473Y140976D02*
X5550Y145700D01*
G01X10711Y140976D02*
X5501Y145973D01*
G01X10788Y141128D02*
X5454Y146246D01*
G01X10741Y141402D02*
X5406Y146519D01*
G01X10692Y141675D02*
X5357Y146793D01*
G01X5310Y147066D02*
X10644Y141949D01*
G01X11028Y141808D02*
X5262Y147338D01*
G01X11702Y141388D02*
X5215Y147611D01*
G01X12176Y141161D02*
X5166Y147885D01*
G01X12581Y140999D02*
X5119Y148158D01*
G01X12918Y140904D02*
X5071Y148431D01*
G01X13254Y140808D02*
X5022Y148704D01*
G01X13573Y140730D02*
X4975Y148978D01*
G01X13837Y140703D02*
X4927Y149251D01*
G01X14100Y140679D02*
X4880Y149524D01*
G01X14363Y140652D02*
X4831Y149796D01*
G01X14628Y140627D02*
X4784Y150070D01*
G01X14861Y140630D02*
X4736Y150343D01*
G01X15089Y140638D02*
X4687Y150616D01*
G01X4640Y150889D02*
X15312Y140652D01*
G01X4592Y151163D02*
X9926Y146047D01*
G01X15523Y140676D02*
X10886Y145125D01*
G01X15733Y140702D02*
X11458Y144803D01*
G01X4544Y151436D02*
X9878Y146320D01*
G01X4496Y151709D02*
X9829Y146592D01*
G01X15935Y140734D02*
X11839Y144664D01*
G01X4449Y151981D02*
X9782Y146865D01*
G01X16131Y140774D02*
X12220Y144525D01*
G01X4401Y152255D02*
X9734Y147139D01*
G01X16326Y140814D02*
X12503Y144483D01*
G01X4375Y152506D02*
X9685Y147412D01*
G01X16512Y140865D02*
X12775Y144449D01*
G01X4356Y152752D02*
X9638Y147685D01*
G01X16692Y140918D02*
X13046Y144416D01*
G01X16873Y140972D02*
X13315Y144385D01*
G01X4336Y152998D02*
X9591Y147958D01*
G01X17042Y141037D02*
X13535Y144401D01*
G01X4316Y153245D02*
X9666Y148112D01*
G01X17209Y141105D02*
X13754Y144418D01*
G01X4295Y153493D02*
X9809Y148204D01*
G01X17376Y141172D02*
X13971Y144437D01*
G01X4294Y153721D02*
X9958Y148287D01*
G01X17532Y141249D02*
X14157Y144486D01*
G01X4321Y153921D02*
X10110Y148368D01*
G01X17685Y141330D02*
X14343Y144534D01*
G01X4348Y154123D02*
X10275Y148437D01*
G01X17837Y141411D02*
X14521Y144593D01*
G01X4377Y154324D02*
X10445Y148502D01*
G01X17982Y141499D02*
X14673Y144673D01*
G01X4404Y154524D02*
X10624Y148557D01*
G01X18119Y141593D02*
X14826Y144753D01*
G01X18259Y141688D02*
X14959Y144854D01*
G01X18392Y141788D02*
X15078Y144966D01*
G01X18515Y141895D02*
X15195Y145082D01*
G01X18640Y142003D02*
X15282Y145225D01*
G01X18762Y142114D02*
X15367Y145370D01*
G01X18872Y142236D02*
X15427Y145541D01*
G01X18980Y142358D02*
X15478Y145718D01*
G01X19090Y142481D02*
X15507Y145917D01*
G01X19185Y142616D02*
X15523Y146130D01*
G01X19280Y142753D02*
X15511Y146369D01*
G01X19374Y142890D02*
X15485Y146620D01*
G01X19457Y143038D02*
X15367Y146961D01*
G01X19534Y143191D02*
X15241Y147309D01*
G01X14075Y148428D02*
X10301Y152048D01*
G01X19611Y143344D02*
X14579Y148172D01*
G01X14540Y148209D02*
X10502Y152083D01*
G01X19682Y143504D02*
X10701Y152118D01*
G01X19741Y143674D02*
X10902Y152153D01*
G01X19801Y143844D02*
X11111Y152181D01*
G01X19855Y144019D02*
X11335Y152192D01*
G01X19896Y144207D02*
X11560Y152204D01*
G01X19935Y144395D02*
X11784Y152216D01*
G01X19973Y144586D02*
X12007Y152228D01*
G01X19992Y144796D02*
X12252Y152222D01*
G01X20011Y145005D02*
X12504Y152206D01*
G01X12758Y152191D02*
X20029Y145215D01*
G01X20023Y145448D02*
X13011Y152174D01*
G01X20018Y145680D02*
X13265Y152159D01*
G01X20011Y145914D02*
X13521Y152140D01*
G01X19979Y146173D02*
X13818Y152082D01*
G01X19945Y146432D02*
X14117Y152023D01*
G01X19901Y146702D02*
X14415Y151964D01*
G01X19815Y147012D02*
X14712Y151906D01*
G01X19728Y147322D02*
X15055Y151805D01*
G01X19640Y147633D02*
X15430Y151673D01*
G01X19553Y147944D02*
X15804Y151540D01*
G01X19318Y148397D02*
X16227Y151363D01*
G01X7632Y140976D02*
X7395D01*
G01X8105D02*
X7869D01*
G01D02*
X7632D01*
G01X8579D02*
X8341D01*
G01D02*
X8105D01*
G01X6684D02*
X6447D01*
G01D02*
X6377D01*
X6364Y141056D01*
G01X8816Y140976D02*
X8579D01*
G01X7395D02*
X7157D01*
G01X6921D02*
X6684D01*
G01X7157D02*
X6921D01*
G01X10711D02*
X10473D01*
G01X10692Y141675D02*
X10741Y141402D01*
G01X10788Y141128D02*
X10815Y140976D01*
X10711D01*
G01X10741Y141402D02*
X10788Y141128D01*
G01X9289Y140976D02*
X9053D01*
G01X9527D02*
X9289D01*
G01X9053D02*
X8816D01*
G01X10236D02*
X10000D01*
G01D02*
X9764D01*
G01D02*
X9527D01*
G01X5357Y146793D02*
X5310Y147066D01*
G01D02*
X5262Y147338D01*
G01D02*
X5215Y147611D01*
G01X5454Y146246D02*
X5406Y146519D01*
G01X5501Y145973D02*
X5454Y146246D01*
G01X5406Y146519D02*
X5357Y146793D01*
G01X5550Y145700D02*
X5501Y145973D01*
G01X5071Y148431D02*
X5022Y148704D01*
G01X6364Y141056D02*
X6315Y141330D01*
G01X5119Y148158D02*
X5071Y148431D01*
G01X5215Y147611D02*
X5166Y147885D01*
G01D02*
X5119Y148158D01*
G01X6173Y142148D02*
X6124Y142422D01*
G01X5597Y145426D02*
X5550Y145700D01*
G01X6076Y142696D02*
X6029Y142968D01*
G01X6124Y142422D02*
X6076Y142696D01*
G01X6220Y141876D02*
X6173Y142148D01*
G01X6315Y141330D02*
X6267Y141604D01*
G01D02*
X6220Y141876D01*
G01X5741Y144607D02*
X5692Y144881D01*
G01X5645Y145153D02*
X5597Y145426D01*
G01X5789Y144334D02*
X5741Y144607D01*
G01X5692Y144881D02*
X5645Y145153D01*
G01X5980Y143241D02*
X5932Y143515D01*
G01X6029Y142968D02*
X5980Y143241D01*
G01X5932Y143515D02*
X5885Y143789D01*
G01D02*
X5836Y144061D01*
G01D02*
X5789Y144334D01*
G01X10473Y140976D02*
X10236D01*
G01X9685Y147412D02*
X9734Y147139D01*
G01D02*
X9782Y146865D01*
G01X9591Y147958D02*
X9638Y147685D01*
G01D02*
X9685Y147412D01*
G01X9878Y146320D02*
X9926Y146047D01*
G01X9782Y146865D02*
X9829Y146592D01*
G01D02*
X9878Y146320D01*
G01X10644Y141949D02*
X10692Y141675D01*
G01X6447Y140976D02*
X6364Y141056D01*
G01X6684Y140976D02*
X6315Y141330D01*
G01X6921Y140976D02*
X6267Y141604D01*
G01X7157Y140976D02*
X6220Y141876D01*
G01X7395Y140976D02*
X6173Y142148D01*
G01X7632Y140976D02*
X6124Y142422D01*
G01X7869Y140976D02*
X6076Y142696D01*
G01X8105Y140976D02*
X6029Y142968D01*
G01X8341Y140976D02*
X5980Y143241D01*
G01X8579Y140976D02*
X5932Y143515D01*
G01X8816Y140976D02*
X5885Y143789D01*
G01X9053Y140976D02*
X5836Y144061D01*
G01X9289Y140976D02*
X5789Y144334D01*
G01X9527Y140976D02*
X5741Y144607D01*
G01X9764Y140976D02*
X5692Y144881D01*
G01X10000Y140976D02*
X5645Y145153D01*
G01X10236Y140976D02*
X5597Y145426D01*
G01X10473Y140976D02*
X5550Y145700D01*
G01X10711Y140976D02*
X5501Y145973D01*
G01X10788Y141128D02*
X5454Y146246D01*
G01X10741Y141402D02*
X5406Y146519D01*
G01X10692Y141675D02*
X5357Y146793D01*
G01X5310Y147066D02*
X10644Y141949D01*
G01X11028Y141808D02*
X5262Y147338D01*
G01X11702Y141388D02*
X5215Y147611D01*
G01X12176Y141161D02*
X5166Y147885D01*
G01X12581Y140999D02*
X5119Y148158D01*
G01X12918Y140904D02*
X5071Y148431D01*
G01X13254Y140808D02*
X5022Y148704D01*
G01X13573Y140730D02*
X4975Y148978D01*
G01X13837Y140703D02*
X4927Y149251D01*
G01X14100Y140679D02*
X4880Y149524D01*
G01X14363Y140652D02*
X4831Y149796D01*
G01X14628Y140627D02*
X4784Y150070D01*
G01X14861Y140630D02*
X4736Y150343D01*
G01X15089Y140638D02*
X4687Y150616D01*
G01X4640Y150889D02*
X15312Y140652D01*
G01X4592Y151163D02*
X9926Y146047D01*
G01X15523Y140676D02*
X10886Y145125D01*
G01X15733Y140702D02*
X11458Y144803D01*
G01X4544Y151436D02*
X9878Y146320D01*
G01X4496Y151709D02*
X9829Y146592D01*
G01X15935Y140734D02*
X11839Y144664D01*
G01X4449Y151981D02*
X9782Y146865D01*
G01X16131Y140774D02*
X12220Y144525D01*
G01X4401Y152255D02*
X9734Y147139D01*
G01X16326Y140814D02*
X12503Y144483D01*
G01X4375Y152506D02*
X9685Y147412D01*
G01X16512Y140865D02*
X12775Y144449D01*
G01X4356Y152752D02*
X9638Y147685D01*
G01X16692Y140918D02*
X13046Y144416D01*
G01X16873Y140972D02*
X13315Y144385D01*
G01X4336Y152998D02*
X9591Y147958D01*
G01X17042Y141037D02*
X13535Y144401D01*
G01X4316Y153245D02*
X9666Y148112D01*
G01X17209Y141105D02*
X13754Y144418D01*
G01X4295Y153493D02*
X9809Y148204D01*
G01X17376Y141172D02*
X13971Y144437D01*
G01X4294Y153721D02*
X9958Y148287D01*
G01X17532Y141249D02*
X14157Y144486D01*
G01X4321Y153921D02*
X10110Y148368D01*
G01X17685Y141330D02*
X14343Y144534D01*
G01X4348Y154123D02*
X10275Y148437D01*
G01X17837Y141411D02*
X14521Y144593D01*
G01X4377Y154324D02*
X10445Y148502D01*
G01X17982Y141499D02*
X14673Y144673D01*
G01X4404Y154524D02*
X10624Y148557D01*
G01X18119Y141593D02*
X14826Y144753D01*
G01X18259Y141688D02*
X14959Y144854D01*
G01X18392Y141788D02*
X15078Y144966D01*
G01X18515Y141895D02*
X15195Y145082D01*
G01X18640Y142003D02*
X15282Y145225D01*
G01X18762Y142114D02*
X15367Y145370D01*
G01X18872Y142236D02*
X15427Y145541D01*
G01X18980Y142358D02*
X15478Y145718D01*
G01X19090Y142481D02*
X15507Y145917D01*
G01X19185Y142616D02*
X15523Y146130D01*
G01X19280Y142753D02*
X15511Y146369D01*
G01X19374Y142890D02*
X15485Y146620D01*
G01X19457Y143038D02*
X15367Y146961D01*
G01X19534Y143191D02*
X15241Y147309D01*
G01X14075Y148428D02*
X10301Y152048D01*
G01X19611Y143344D02*
X14579Y148172D01*
G01X14540Y148209D02*
X10502Y152083D01*
G01X19682Y143504D02*
X10701Y152118D01*
G01X19741Y143674D02*
X10902Y152153D01*
G01X19801Y143844D02*
X11111Y152181D01*
G01X19855Y144019D02*
X11335Y152192D01*
G01X19896Y144207D02*
X11560Y152204D01*
G01X19935Y144395D02*
X11784Y152216D01*
G01X19973Y144586D02*
X12007Y152228D01*
G01X19992Y144796D02*
X12252Y152222D01*
G01X20011Y145005D02*
X12504Y152206D01*
G01X12758Y152191D02*
X20029Y145215D01*
G01X20023Y145448D02*
X13011Y152174D01*
G01X20018Y145680D02*
X13265Y152159D01*
G01X20011Y145914D02*
X13521Y152140D01*
G01X19979Y146173D02*
X13818Y152082D01*
G01X19945Y146432D02*
X14117Y152023D01*
G01X19901Y146702D02*
X14415Y151964D01*
G01X19815Y147012D02*
X14712Y151906D01*
G01X19728Y147322D02*
X15055Y151805D01*
G01X19640Y147633D02*
X15430Y151673D01*
G01X19553Y147944D02*
X15804Y151540D01*
G01X19318Y148397D02*
X16227Y151363D01*
G01X7632Y140976D02*
X7395D01*
G01X8105D02*
X7869D01*
G01D02*
X7632D01*
G01X8579D02*
X8341D01*
G01D02*
X8105D01*
G01X6684D02*
X6447D01*
G01D02*
X6377D01*
X6364Y141056D01*
G01X8816Y140976D02*
X8579D01*
G01X7395D02*
X7157D01*
G01X6921D02*
X6684D01*
G01X7157D02*
X6921D01*
G01X10711D02*
X10473D01*
G01X10692Y141675D02*
X10741Y141402D01*
G01X10788Y141128D02*
X10815Y140976D01*
X10711D01*
G01X10741Y141402D02*
X10788Y141128D01*
G01X9289Y140976D02*
X9053D01*
G01X9527D02*
X9289D01*
G01X9053D02*
X8816D01*
G01X10236D02*
X10000D01*
G01D02*
X9764D01*
G01D02*
X9527D01*
G01X5357Y146793D02*
X5310Y147066D01*
G01D02*
X5262Y147338D01*
G01D02*
X5215Y147611D01*
G01X5454Y146246D02*
X5406Y146519D01*
G01X5501Y145973D02*
X5454Y146246D01*
G01X5406Y146519D02*
X5357Y146793D01*
G01X5550Y145700D02*
X5501Y145973D01*
G01X5071Y148431D02*
X5022Y148704D01*
G01X6364Y141056D02*
X6315Y141330D01*
G01X5119Y148158D02*
X5071Y148431D01*
G01X5215Y147611D02*
X5166Y147885D01*
G01D02*
X5119Y148158D01*
G01X6173Y142148D02*
X6124Y142422D01*
G01X5597Y145426D02*
X5550Y145700D01*
G01X6076Y142696D02*
X6029Y142968D01*
G01X6124Y142422D02*
X6076Y142696D01*
G01X6220Y141876D02*
X6173Y142148D01*
G01X6315Y141330D02*
X6267Y141604D01*
G01D02*
X6220Y141876D01*
G01X5741Y144607D02*
X5692Y144881D01*
G01X5645Y145153D02*
X5597Y145426D01*
G01X5789Y144334D02*
X5741Y144607D01*
G01X5692Y144881D02*
X5645Y145153D01*
G01X5980Y143241D02*
X5932Y143515D01*
G01X6029Y142968D02*
X5980Y143241D01*
G01X5932Y143515D02*
X5885Y143789D01*
G01D02*
X5836Y144061D01*
G01D02*
X5789Y144334D01*
G01X10473Y140976D02*
X10236D01*
G01X9685Y147412D02*
X9734Y147139D01*
G01D02*
X9782Y146865D01*
G01X9591Y147958D02*
X9638Y147685D01*
G01D02*
X9685Y147412D01*
G01X9878Y146320D02*
X9926Y146047D01*
G01X9782Y146865D02*
X9829Y146592D01*
G01D02*
X9878Y146320D01*
G01X10644Y141949D02*
X10692Y141675D01*
G01X4431Y154725D02*
X10810Y148605D01*
G01X4478Y154907D02*
X11005Y148646D01*
G01X4546Y155070D02*
X11209Y148679D01*
G01X4613Y155232D02*
X11416Y148706D01*
G01X4679Y155395D02*
X11632Y148725D01*
G01X4746Y155559D02*
X11854Y148740D01*
G01X4813Y155722D02*
X8919Y151783D01*
G01X9091Y151619D02*
X12081Y148751D01*
G01X4891Y155875D02*
X8870Y152057D01*
G01X9250Y151694D02*
X12311Y148756D01*
G01X9409Y151768D02*
X12545Y148759D01*
G01X9576Y151835D02*
X12817Y148725D01*
G01X9755Y151892D02*
X13091Y148691D01*
G01X13362Y148657D02*
X9932Y151947D01*
G01X13635Y148623D02*
X10110Y152004D01*
G01X19079Y148852D02*
X16776Y151062D01*
G01X4784Y150070D02*
X4736Y150343D01*
G01X4449Y151981D02*
X4401Y152255D01*
G01X4496Y151709D02*
X4449Y151981D01*
G01X4544Y151436D02*
X4496Y151709D01*
G01X4592Y151163D02*
X4544Y151436D01*
G01X4687Y150616D02*
X4640Y150889D01*
G01X4736Y150343D02*
X4687Y150616D01*
G01X4640Y150889D02*
X4592Y151163D01*
G01X5022Y148704D02*
X4975Y148978D01*
G01X4927Y149251D02*
X4880Y149524D01*
G01D02*
X4831Y149796D01*
G01D02*
X4784Y150070D01*
G01X4975Y148978D02*
X4927Y149251D01*
G01X8823Y152330D02*
X8870Y152057D01*
G01D02*
X8919Y151783D01*
G01X4431Y154725D02*
X10810Y148605D01*
G01X4478Y154907D02*
X11005Y148646D01*
G01X4546Y155070D02*
X11209Y148679D01*
G01X4613Y155232D02*
X11416Y148706D01*
G01X4679Y155395D02*
X11632Y148725D01*
G01X4746Y155559D02*
X11854Y148740D01*
G01X4813Y155722D02*
X8919Y151783D01*
G01X9091Y151619D02*
X12081Y148751D01*
G01X4891Y155875D02*
X8870Y152057D01*
G01X9250Y151694D02*
X12311Y148756D01*
G01X9409Y151768D02*
X12545Y148759D01*
G01X9576Y151835D02*
X12817Y148725D01*
G01X9755Y151892D02*
X13091Y148691D01*
G01X13362Y148657D02*
X9932Y151947D01*
G01X13635Y148623D02*
X10110Y152004D01*
G01X19079Y148852D02*
X16776Y151062D01*
G01X4784Y150070D02*
X4736Y150343D01*
G01X4449Y151981D02*
X4401Y152255D01*
G01X4496Y151709D02*
X4449Y151981D01*
G01X4544Y151436D02*
X4496Y151709D01*
G01X4592Y151163D02*
X4544Y151436D01*
G01X4687Y150616D02*
X4640Y150889D01*
G01X4736Y150343D02*
X4687Y150616D01*
G01X4640Y150889D02*
X4592Y151163D01*
G01X5022Y148704D02*
X4975Y148978D01*
G01X4927Y149251D02*
X4880Y149524D01*
G01D02*
X4831Y149796D01*
G01D02*
X4784Y150070D01*
G01X4975Y148978D02*
X4927Y149251D01*
G01X8823Y152330D02*
X8870Y152057D01*
G01D02*
X8919Y151783D01*
G01X4991Y156005D02*
X8823Y152330D01*
G01X5093Y156135D02*
X8794Y152585D01*
G01X5195Y156266D02*
X8773Y152832D01*
G01X5295Y156395D02*
X8794Y153038D01*
G01X5397Y156525D02*
X8819Y153243D01*
G01X5498Y156656D02*
X8877Y153414D01*
G01X5625Y156761D02*
X8935Y153586D01*
G01X5757Y156861D02*
X9024Y153728D01*
G01X5889Y156961D02*
X9114Y153867D01*
G01X6022Y157061D02*
X9226Y153988D01*
G01X6155Y157162D02*
X9349Y154098D01*
G01X6286Y157261D02*
X9479Y154200D01*
G01X6425Y157356D02*
X9631Y154280D01*
G01X6588Y157428D02*
X9786Y154360D01*
G01X6750Y157500D02*
X9963Y154417D01*
G01X6912Y157571D02*
X10148Y154467D01*
G01X7073Y157643D02*
X10342Y154508D01*
G01X7236Y157715D02*
X10562Y154525D01*
G01X7397Y157787D02*
X10780Y154543D01*
G01X7575Y157845D02*
X11015Y154544D01*
G01X7765Y157888D02*
X11256Y154539D01*
G01X7956Y157932D02*
X11499Y154535D01*
G01X8149Y157976D02*
X11750Y154521D01*
G01X8339Y158020D02*
X12005Y154503D01*
G01X8530Y158064D02*
X12262Y154484D01*
G01X8721Y158108D02*
X12536Y154448D01*
G01X8938Y158127D02*
X12810Y154413D01*
G01X9159Y158142D02*
X13107Y154354D01*
G01X9379Y158157D02*
X13409Y154292D01*
G01X9601Y158173D02*
X13742Y154200D01*
G01X14092Y154091D02*
X9822Y158188D01*
G01X14467Y153959D02*
X10044Y158203D01*
G01X14883Y153787D02*
X10270Y158212D01*
G01X15332Y153584D02*
X10514Y158205D01*
G01X15691Y153466D02*
X10758Y158199D01*
G01X15755Y153633D02*
X11002Y158192D01*
G01X15817Y153799D02*
X11251Y158181D01*
G01X15880Y153967D02*
X11511Y158157D01*
G01X15944Y154134D02*
X11773Y158134D01*
G01X16006Y154301D02*
X12035Y158111D01*
G01X16068Y154467D02*
X12313Y158070D01*
G01X16132Y154634D02*
X12596Y158025D01*
G01X16195Y154802D02*
X12881Y157980D01*
G01X16257Y154968D02*
X13189Y157912D01*
G01X16321Y155135D02*
X13501Y157839D01*
G01X16383Y155302D02*
X13824Y157757D01*
G01X16445Y155469D02*
X14175Y157648D01*
G01X16509Y155636D02*
X14526Y157538D01*
G01X16572Y155803D02*
X14920Y157387D01*
G01X16634Y155970D02*
X15320Y157230D01*
G01X16698Y156137D02*
X15766Y157031D01*
G01X16760Y156304D02*
X16228Y156814D01*
G01X16822Y156470D02*
X16723Y156566D01*
G01X16509Y155636D02*
X16445Y155469D01*
G01X16572Y155803D02*
X16509Y155636D01*
G01X16321Y155135D02*
X16257Y154968D01*
G01X16445Y155469D02*
X16383Y155302D01*
G01X16257Y154968D02*
X16195Y154802D01*
G01X16634Y155970D02*
X16572Y155803D01*
G01X16383Y155302D02*
X16321Y155135D01*
G01X16698Y156137D02*
X16634Y155970D01*
G01X16822Y156470D02*
X16760Y156304D01*
G01D02*
X16698Y156137D01*
G01X15755Y153633D02*
X15691Y153466D01*
G01X15817Y153799D02*
X15755Y153633D01*
G01X16132Y154634D02*
X16068Y154467D01*
G01D02*
X16006Y154301D01*
G01X16195Y154802D02*
X16132Y154634D01*
G01X15880Y153967D02*
X15817Y153799D01*
G01X15944Y154134D02*
X15880Y153967D01*
G01X16006Y154301D02*
X15944Y154134D01*
G01X4991Y156005D02*
X8823Y152330D01*
G01X5093Y156135D02*
X8794Y152585D01*
G01X5195Y156266D02*
X8773Y152832D01*
G01X5295Y156395D02*
X8794Y153038D01*
G01X5397Y156525D02*
X8819Y153243D01*
G01X5498Y156656D02*
X8877Y153414D01*
G01X5625Y156761D02*
X8935Y153586D01*
G01X5757Y156861D02*
X9024Y153728D01*
G01X5889Y156961D02*
X9114Y153867D01*
G01X6022Y157061D02*
X9226Y153988D01*
G01X6155Y157162D02*
X9349Y154098D01*
G01X6286Y157261D02*
X9479Y154200D01*
G01X6425Y157356D02*
X9631Y154280D01*
G01X6588Y157428D02*
X9786Y154360D01*
G01X6750Y157500D02*
X9963Y154417D01*
G01X6912Y157571D02*
X10148Y154467D01*
G01X7073Y157643D02*
X10342Y154508D01*
G01X7236Y157715D02*
X10562Y154525D01*
G01X7397Y157787D02*
X10780Y154543D01*
G01X7575Y157845D02*
X11015Y154544D01*
G01X7765Y157888D02*
X11256Y154539D01*
G01X7956Y157932D02*
X11499Y154535D01*
G01X8149Y157976D02*
X11750Y154521D01*
G01X8339Y158020D02*
X12005Y154503D01*
G01X8530Y158064D02*
X12262Y154484D01*
G01X8721Y158108D02*
X12536Y154448D01*
G01X8938Y158127D02*
X12810Y154413D01*
G01X9159Y158142D02*
X13107Y154354D01*
G01X9379Y158157D02*
X13409Y154292D01*
G01X9601Y158173D02*
X13742Y154200D01*
G01X14092Y154091D02*
X9822Y158188D01*
G01X14467Y153959D02*
X10044Y158203D01*
G01X14883Y153787D02*
X10270Y158212D01*
G01X15332Y153584D02*
X10514Y158205D01*
G01X15691Y153466D02*
X10758Y158199D01*
G01X15755Y153633D02*
X11002Y158192D01*
G01X15817Y153799D02*
X11251Y158181D01*
G01X15880Y153967D02*
X11511Y158157D01*
G01X15944Y154134D02*
X11773Y158134D01*
G01X16006Y154301D02*
X12035Y158111D01*
G01X16068Y154467D02*
X12313Y158070D01*
G01X16132Y154634D02*
X12596Y158025D01*
G01X16195Y154802D02*
X12881Y157980D01*
G01X16257Y154968D02*
X13189Y157912D01*
G01X16321Y155135D02*
X13501Y157839D01*
G01X16383Y155302D02*
X13824Y157757D01*
G01X16445Y155469D02*
X14175Y157648D01*
G01X16509Y155636D02*
X14526Y157538D01*
G01X16572Y155803D02*
X14920Y157387D01*
G01X16634Y155970D02*
X15320Y157230D01*
G01X16698Y156137D02*
X15766Y157031D01*
G01X16760Y156304D02*
X16228Y156814D01*
G01X16822Y156470D02*
X16723Y156566D01*
G01X16509Y155636D02*
X16445Y155469D01*
G01X16572Y155803D02*
X16509Y155636D01*
G01X16321Y155135D02*
X16257Y154968D01*
G01X16445Y155469D02*
X16383Y155302D01*
G01X16257Y154968D02*
X16195Y154802D01*
G01X16634Y155970D02*
X16572Y155803D01*
G01X16383Y155302D02*
X16321Y155135D01*
G01X16698Y156137D02*
X16634Y155970D01*
G01X16822Y156470D02*
X16760Y156304D01*
G01D02*
X16698Y156137D01*
G01X15755Y153633D02*
X15691Y153466D01*
G01X15817Y153799D02*
X15755Y153633D01*
G01X16132Y154634D02*
X16068Y154467D01*
G01D02*
X16006Y154301D01*
G01X16195Y154802D02*
X16132Y154634D01*
G01X15880Y153967D02*
X15817Y153799D01*
G01X15944Y154134D02*
X15880Y153967D01*
G01X16006Y154301D02*
X15944Y154134D01*
G01X23987Y141419D02*
X23494Y141891D01*
G01X24471Y141181D02*
X23390Y142219D01*
G01X24857Y141038D02*
X23285Y142546D01*
G01X25229Y140908D02*
X23182Y142873D01*
G01X25537Y140839D02*
X23078Y143199D01*
G01X25846Y140771D02*
X22973Y143526D01*
G01X26154Y140703D02*
X22869Y143854D01*
G01X26412Y140682D02*
X22766Y144180D01*
G01X26670Y140663D02*
X22662Y144507D01*
G01X26927Y140644D02*
X22558Y144834D01*
G01X27185Y140622D02*
X22454Y145162D01*
G01X27399Y140644D02*
X22350Y145488D01*
G01X27614Y140665D02*
X22246Y145815D01*
G01X27829Y140687D02*
X22142Y146142D01*
G01X28043Y140709D02*
X22995Y145551D01*
G01X28237Y140749D02*
X23587Y145210D01*
G01X28412Y140809D02*
X24000Y145041D01*
G01X28587Y140867D02*
X24354Y144929D01*
G01X28764Y140927D02*
X24624Y144897D01*
G01X28937Y140985D02*
X24890Y144869D01*
G01X29086Y141069D02*
X25114Y144881D01*
G01X29228Y141162D02*
X25324Y144907D01*
G01X29370Y141254D02*
X25518Y144949D01*
G01X29510Y141346D02*
X25682Y145018D01*
G01X29651Y141438D02*
X25834Y145100D01*
G01X29766Y141556D02*
X25951Y145214D01*
G01X29876Y141678D02*
X26051Y145346D01*
G01X29986Y141799D02*
X26128Y145499D01*
G01X30096Y141921D02*
X26179Y145678D01*
G01X30205Y142043D02*
X26216Y145869D01*
G01X30288Y142191D02*
X26223Y146089D01*
G01X30367Y142342D02*
X26225Y146316D01*
G01X30447Y142492D02*
X26196Y146569D01*
G01X30527Y142643D02*
X26164Y146828D01*
G01X30607Y142794D02*
X26120Y147098D01*
G01X30656Y142974D02*
X26071Y147371D01*
G01X30705Y143154D02*
X26024Y147644D01*
G01X30753Y143335D02*
X25975Y147918D01*
G01X30802Y143516D02*
X25928Y148192D01*
G01X30844Y143702D02*
X25880Y148464D01*
G01X30858Y143915D02*
X25831Y148737D01*
G01X30873Y144128D02*
X25784Y149011D01*
G01X30888Y144342D02*
X25735Y149285D01*
G01X30903Y144555D02*
X25688Y149557D01*
G01X30893Y144791D02*
X25640Y149830D01*
G01X30869Y145042D02*
X25591Y150104D01*
G01X30843Y145294D02*
X25544Y150377D01*
G01X30819Y145544D02*
X25495Y150651D01*
G01X30785Y145803D02*
X25447Y150923D01*
G01X30737Y146076D02*
X25400Y151197D01*
G01X30690Y146350D02*
X25351Y151471D01*
G01X25304Y151744D02*
X30641Y146623D01*
G01X30593Y146896D02*
X25255Y152016D01*
G01X30546Y147169D02*
X25207Y152290D01*
G01X30497Y147443D02*
X25159Y152564D01*
G01X30450Y147716D02*
X25111Y152836D01*
G01X30402Y147988D02*
X25064Y153110D01*
G01X30355Y148262D02*
X25015Y153383D01*
G01X30306Y148535D02*
X24967Y153657D01*
G01X30690Y146350D02*
X30737Y146076D01*
G01X30258Y148808D02*
X30306Y148535D01*
G01X22766Y144180D02*
X22869Y143854D01*
G01X22662Y144507D02*
X22766Y144180D01*
G01X22869Y143854D02*
X22973Y143526D01*
G01X22558Y144834D02*
X22662Y144507D01*
G01X22973Y143526D02*
X23078Y143199D01*
G01X22454Y145162D02*
X22558Y144834D01*
G01X23078Y143199D02*
X23182Y142873D01*
G01D02*
X23285Y142546D01*
G01D02*
X23390Y142219D01*
G01X30306Y148535D02*
X30355Y148262D01*
G01X22350Y145488D02*
X22454Y145162D01*
G01X30355Y148262D02*
X30402Y147988D01*
G01X22246Y145815D02*
X22350Y145488D01*
G01X22142Y146142D02*
X22246Y145815D01*
G01X23390Y142219D02*
X23494Y141891D01*
G01X30450Y147716D02*
X30497Y147443D01*
G01D02*
X30546Y147169D01*
G01X30402Y147988D02*
X30450Y147716D01*
G01X30546Y147169D02*
X30593Y146896D01*
G01X30690Y146350D02*
X30641Y146623D01*
G01X26024Y147644D02*
X26071Y147371D01*
G01D02*
X26120Y147098D01*
G01X30593Y146896D02*
X30641Y146623D01*
G01X25975Y147918D02*
X25928Y148192D01*
G01D02*
X25880Y148464D01*
G01X30737Y146076D02*
X30785Y145803D01*
G01X25975Y147918D02*
X26024Y147644D01*
G01X25880Y148464D02*
X25831Y148737D01*
G01X23987Y141419D02*
X23494Y141891D01*
G01X24471Y141181D02*
X23390Y142219D01*
G01X24857Y141038D02*
X23285Y142546D01*
G01X25229Y140908D02*
X23182Y142873D01*
G01X25537Y140839D02*
X23078Y143199D01*
G01X25846Y140771D02*
X22973Y143526D01*
G01X26154Y140703D02*
X22869Y143854D01*
G01X26412Y140682D02*
X22766Y144180D01*
G01X26670Y140663D02*
X22662Y144507D01*
G01X26927Y140644D02*
X22558Y144834D01*
G01X27185Y140622D02*
X22454Y145162D01*
G01X27399Y140644D02*
X22350Y145488D01*
G01X27614Y140665D02*
X22246Y145815D01*
G01X27829Y140687D02*
X22142Y146142D01*
G01X28043Y140709D02*
X22995Y145551D01*
G01X28237Y140749D02*
X23587Y145210D01*
G01X28412Y140809D02*
X24000Y145041D01*
G01X28587Y140867D02*
X24354Y144929D01*
G01X28764Y140927D02*
X24624Y144897D01*
G01X28937Y140985D02*
X24890Y144869D01*
G01X29086Y141069D02*
X25114Y144881D01*
G01X29228Y141162D02*
X25324Y144907D01*
G01X29370Y141254D02*
X25518Y144949D01*
G01X29510Y141346D02*
X25682Y145018D01*
G01X29651Y141438D02*
X25834Y145100D01*
G01X29766Y141556D02*
X25951Y145214D01*
G01X29876Y141678D02*
X26051Y145346D01*
G01X29986Y141799D02*
X26128Y145499D01*
G01X30096Y141921D02*
X26179Y145678D01*
G01X30205Y142043D02*
X26216Y145869D01*
G01X30288Y142191D02*
X26223Y146089D01*
G01X30367Y142342D02*
X26225Y146316D01*
G01X30447Y142492D02*
X26196Y146569D01*
G01X30527Y142643D02*
X26164Y146828D01*
G01X30607Y142794D02*
X26120Y147098D01*
G01X30656Y142974D02*
X26071Y147371D01*
G01X30705Y143154D02*
X26024Y147644D01*
G01X30753Y143335D02*
X25975Y147918D01*
G01X30802Y143516D02*
X25928Y148192D01*
G01X30844Y143702D02*
X25880Y148464D01*
G01X30858Y143915D02*
X25831Y148737D01*
G01X30873Y144128D02*
X25784Y149011D01*
G01X30888Y144342D02*
X25735Y149285D01*
G01X30903Y144555D02*
X25688Y149557D01*
G01X30893Y144791D02*
X25640Y149830D01*
G01X30869Y145042D02*
X25591Y150104D01*
G01X30843Y145294D02*
X25544Y150377D01*
G01X30819Y145544D02*
X25495Y150651D01*
G01X30785Y145803D02*
X25447Y150923D01*
G01X30737Y146076D02*
X25400Y151197D01*
G01X30690Y146350D02*
X25351Y151471D01*
G01X25304Y151744D02*
X30641Y146623D01*
G01X30593Y146896D02*
X25255Y152016D01*
G01X30546Y147169D02*
X25207Y152290D01*
G01X30497Y147443D02*
X25159Y152564D01*
G01X30450Y147716D02*
X25111Y152836D01*
G01X30402Y147988D02*
X25064Y153110D01*
G01X30355Y148262D02*
X25015Y153383D01*
G01X30306Y148535D02*
X24967Y153657D01*
G01X30690Y146350D02*
X30737Y146076D01*
G01X30258Y148808D02*
X30306Y148535D01*
G01X22766Y144180D02*
X22869Y143854D01*
G01X22662Y144507D02*
X22766Y144180D01*
G01X22869Y143854D02*
X22973Y143526D01*
G01X22558Y144834D02*
X22662Y144507D01*
G01X22973Y143526D02*
X23078Y143199D01*
G01X22454Y145162D02*
X22558Y144834D01*
G01X23078Y143199D02*
X23182Y142873D01*
G01D02*
X23285Y142546D01*
G01D02*
X23390Y142219D01*
G01X30306Y148535D02*
X30355Y148262D01*
G01X22350Y145488D02*
X22454Y145162D01*
G01X30355Y148262D02*
X30402Y147988D01*
G01X22246Y145815D02*
X22350Y145488D01*
G01X22142Y146142D02*
X22246Y145815D01*
G01X23390Y142219D02*
X23494Y141891D01*
G01X30450Y147716D02*
X30497Y147443D01*
G01D02*
X30546Y147169D01*
G01X30402Y147988D02*
X30450Y147716D01*
G01X30546Y147169D02*
X30593Y146896D01*
G01X30690Y146350D02*
X30641Y146623D01*
G01X26024Y147644D02*
X26071Y147371D01*
G01D02*
X26120Y147098D01*
G01X30593Y146896D02*
X30641Y146623D01*
G01X25975Y147918D02*
X25928Y148192D01*
G01D02*
X25880Y148464D01*
G01X30737Y146076D02*
X30785Y145803D01*
G01X25975Y147918D02*
X26024Y147644D01*
G01X25880Y148464D02*
X25831Y148737D01*
G01X30258Y148808D02*
X20821Y157861D01*
G01X21057D02*
X30211Y149081D01*
G01X21294Y157861D02*
X30162Y149355D01*
G01X21532Y157861D02*
X30115Y149628D01*
G01X21769Y157861D02*
X30067Y149901D01*
G01X22005Y157861D02*
X30018Y150173D01*
G01X22242Y157861D02*
X29971Y150447D01*
G01X22480Y157861D02*
X29923Y150721D01*
G01X22716Y157861D02*
X29875Y150994D01*
G01X22953Y157861D02*
X29827Y151266D01*
G01X23189Y157861D02*
X29780Y151540D01*
G01X23427Y157861D02*
X29731Y151813D01*
G01X23664Y157861D02*
X29683Y152086D01*
G01X25447Y150923D02*
X25400Y151197D01*
G01X25304Y151744D02*
X25351Y151471D01*
G01D02*
X25400Y151197D01*
G01X25784Y149011D02*
X25735Y149285D01*
G01X25255Y152016D02*
X25207Y152290D01*
G01X25831Y148737D02*
X25784Y149011D01*
G01X25304Y151744D02*
X25255Y152016D01*
G01X25544Y150377D02*
X25495Y150651D01*
G01X25735Y149285D02*
X25688Y149557D01*
G01X25591Y150104D02*
X25544Y150377D01*
G01X25688Y149557D02*
X25640Y149830D01*
G01D02*
X25591Y150104D01*
G01X25495Y150651D02*
X25447Y150923D01*
G01X29636Y152359D02*
X29683Y152086D01*
G01D02*
X29731Y151813D01*
G01X30162Y149355D02*
X30211Y149081D01*
G01X30067Y149901D02*
X30115Y149628D01*
G01D02*
X30162Y149355D01*
G01X30211Y149081D02*
X30258Y148808D01*
G01X30018Y150173D02*
X30067Y149901D01*
G01X29875Y150994D02*
X29923Y150721D01*
G01X29827Y151266D02*
X29875Y150994D01*
G01X29780Y151540D02*
X29827Y151266D01*
G01X29731Y151813D02*
X29780Y151540D01*
G01X29971Y150447D02*
X30018Y150173D01*
G01X29923Y150721D02*
X29971Y150447D01*
G01X30258Y148808D02*
X20821Y157861D01*
G01X21057D02*
X30211Y149081D01*
G01X21294Y157861D02*
X30162Y149355D01*
G01X21532Y157861D02*
X30115Y149628D01*
G01X21769Y157861D02*
X30067Y149901D01*
G01X22005Y157861D02*
X30018Y150173D01*
G01X22242Y157861D02*
X29971Y150447D01*
G01X22480Y157861D02*
X29923Y150721D01*
G01X22716Y157861D02*
X29875Y150994D01*
G01X22953Y157861D02*
X29827Y151266D01*
G01X23189Y157861D02*
X29780Y151540D01*
G01X23427Y157861D02*
X29731Y151813D01*
G01X23664Y157861D02*
X29683Y152086D01*
G01X25447Y150923D02*
X25400Y151197D01*
G01X25304Y151744D02*
X25351Y151471D01*
G01D02*
X25400Y151197D01*
G01X25784Y149011D02*
X25735Y149285D01*
G01X25255Y152016D02*
X25207Y152290D01*
G01X25831Y148737D02*
X25784Y149011D01*
G01X25304Y151744D02*
X25255Y152016D01*
G01X25544Y150377D02*
X25495Y150651D01*
G01X25735Y149285D02*
X25688Y149557D01*
G01X25591Y150104D02*
X25544Y150377D01*
G01X25688Y149557D02*
X25640Y149830D01*
G01D02*
X25591Y150104D01*
G01X25495Y150651D02*
X25447Y150923D01*
G01X29636Y152359D02*
X29683Y152086D01*
G01D02*
X29731Y151813D01*
G01X30162Y149355D02*
X30211Y149081D01*
G01X30067Y149901D02*
X30115Y149628D01*
G01D02*
X30162Y149355D01*
G01X30211Y149081D02*
X30258Y148808D01*
G01X30018Y150173D02*
X30067Y149901D01*
G01X29875Y150994D02*
X29923Y150721D01*
G01X29827Y151266D02*
X29875Y150994D01*
G01X29780Y151540D02*
X29827Y151266D01*
G01X29731Y151813D02*
X29780Y151540D01*
G01X29971Y150447D02*
X30018Y150173D01*
G01X29923Y150721D02*
X29971Y150447D01*
G01X20910Y153685D02*
X20917Y153679D01*
G01X20863Y153959D02*
X21155Y153679D01*
G01X20816Y154231D02*
X21391Y153679D01*
G01X20767Y154504D02*
X21627Y153679D01*
G01X20719Y154777D02*
X21864Y153679D01*
G01X20672Y155051D02*
X22101Y153679D01*
G01X20624Y155324D02*
X22337Y153679D01*
G01X20575Y155597D02*
X22575Y153679D01*
G01X20528Y155870D02*
X22812Y153679D01*
G01X20481Y156144D02*
X23049Y153679D01*
G01X20433Y156416D02*
X23285Y153679D01*
G01X20384Y156689D02*
X23521Y153679D01*
G01X20337Y156962D02*
X23759Y153679D01*
G01X20289Y157236D02*
X23996Y153679D01*
G01X20240Y157508D02*
X24234Y153679D01*
G01X20193Y157781D02*
X24470Y153679D01*
G01X20348Y157861D02*
X24707Y153679D01*
G01X24967Y153657D02*
X24944Y153679D01*
G01X20585Y157861D02*
X24944Y153679D01*
G01X23900Y157861D02*
X29636Y152359D01*
G01X24137Y157861D02*
X29587Y152632D01*
G01X29540Y152906D02*
X24204Y158025D01*
G01X24155Y158298D02*
X29492Y153179D01*
G01X24107Y158571D02*
X29443Y153451D01*
G01Y153679D02*
X24060Y158844D01*
G01X29681Y153679D02*
X24011Y159118D01*
G01X29918Y153679D02*
X23964Y159391D01*
G01X30154Y153679D02*
X23915Y159664D01*
G01X30391Y153679D02*
X23867Y159938D01*
G01X30629Y153679D02*
X23818Y160211D01*
G01X30865Y153679D02*
X23771Y160484D01*
G01X31102Y153679D02*
X23724Y160757D01*
G01X31338Y153679D02*
X23675Y161031D01*
G01X31575Y153679D02*
X23627Y161305D01*
G01X31813Y153679D02*
X23580Y161577D01*
G01X32049Y153679D02*
X23531Y161850D01*
G01X32222Y153740D02*
X23483Y162124D01*
G01X23435Y162398D02*
X32175Y154014D01*
G01X23387Y162671D02*
X32126Y154287D01*
G01X23338Y162943D02*
X32079Y154560D01*
G01X23291Y163217D02*
X28631Y158095D01*
G01X32030Y154834D02*
X28875Y157861D01*
G01X23243Y163490D02*
X28582Y158368D01*
G01X31982Y155107D02*
X29111Y157861D01*
G01X23195Y163764D02*
X28534Y158642D01*
G01X31935Y155380D02*
X29348Y157861D01*
G01X31886Y155653D02*
X29584Y157861D01*
G01X23147Y164036D02*
X28487Y158914D01*
G01X23098Y164310D02*
X28438Y159188D01*
G01X31839Y155927D02*
X29822Y157861D01*
G01X31790Y156200D02*
X30059Y157861D01*
G01X23349Y164297D02*
X28391Y159461D01*
G01X23804Y164089D02*
X28342Y159734D01*
G01X31742Y156473D02*
X30295Y157861D01*
G01X24257Y163880D02*
X28294Y160007D01*
G01X31693Y156746D02*
X30532Y157861D01*
G01X30770D02*
X31646Y157020D01*
G01X24712Y163671D02*
X28247Y160281D01*
G01X25168Y163462D02*
X28198Y160555D01*
G01X31598Y157293D02*
X31006Y157861D01*
G01X31550Y157567D02*
X31243Y157861D01*
G01X25622Y163253D02*
X28151Y160827D01*
G01X31502Y157839D02*
X31479Y157861D01*
G01X26075Y163044D02*
X28103Y161100D01*
G01X26531Y162835D02*
X28054Y161374D01*
G01X26987Y162626D02*
X28007Y161647D01*
G01X27440Y162418D02*
X27958Y161920D01*
G01X27894Y162209D02*
X27911Y162193D01*
G01X25159Y152564D02*
X25111Y152836D01*
G01X31935Y155380D02*
X31886Y155653D01*
G01X25111Y152836D02*
X25064Y153110D01*
G01X31598Y157293D02*
X31550Y157567D01*
G01X31646Y157020D02*
X31693Y156746D01*
G01X29443Y153679D02*
X29404D01*
X29443Y153451D01*
G01X31598Y157293D02*
X31646Y157020D01*
G01X25064Y153110D02*
X25015Y153383D01*
G01X31839Y155927D02*
X31790Y156200D01*
G01X25207Y152290D02*
X25159Y152564D01*
G01X31742Y156473D02*
X31693Y156746D01*
G01X31790Y156200D02*
X31742Y156473D01*
G01X29540Y152906D02*
X29587Y152632D01*
G01X29348Y157861D02*
X29584D01*
G01X29111D02*
X29348D01*
G01X20910Y153685D02*
X20863Y153959D01*
G01X31982Y155107D02*
X31935Y155380D01*
G01X28875Y157861D02*
X29111D01*
G01X32030Y154834D02*
X31982Y155107D01*
G01X20481Y156144D02*
X20433Y156416D01*
G01D02*
X20384Y156689D01*
G01X22812Y153679D02*
X22575D01*
G01X23049D02*
X22812D01*
G01X20575Y155597D02*
X20528Y155870D01*
G01X23285Y153679D02*
X23521D01*
G01X20624Y155324D02*
X20575Y155597D01*
G01X23285Y153679D02*
X23049D01*
G01X22575D02*
X22337D01*
G01X20528Y155870D02*
X20481Y156144D01*
G01X20289Y157236D02*
X20240Y157508D01*
G01X21864Y153679D02*
X21627D01*
G01X22337D02*
X22101D01*
G01D02*
X21864D01*
G01X23521D02*
X23759D01*
G01X20337Y156962D02*
X20289Y157236D01*
G01X20863Y153959D02*
X20816Y154231D01*
G01X20672Y155051D02*
X20624Y155324D01*
G01X23996Y153679D02*
X24234D01*
G01X20767Y154504D02*
X20719Y154777D01*
G01D02*
X20672Y155051D01*
G01X23759Y153679D02*
X23996D01*
G01X24234D02*
X24470D01*
G01X20240Y157508D02*
X20193Y157781D01*
G01X24707Y153679D02*
X24944D01*
G01X20816Y154231D02*
X20767Y154504D01*
G01X24470Y153679D02*
X24707D01*
G01X20384Y156689D02*
X20337Y156962D01*
G01X22953Y157861D02*
X23189D01*
G01X22716D02*
X22953D01*
G01X22242D02*
X22480D01*
G01D02*
X22716D01*
G01X21769D02*
X22005D01*
G01D02*
X22242D01*
G01X23664D02*
X23900D01*
G01X24107Y158571D02*
X24060Y158844D01*
G01D02*
X24011Y159118D01*
G01X21532Y157861D02*
X21769D01*
G01X23189D02*
X23427D01*
G01D02*
X23664D01*
G01X24204Y158025D02*
X24155Y158298D01*
G01D02*
X24107Y158571D01*
G01X23900Y157861D02*
X24137D01*
G01X20910Y153685D02*
X20912Y153679D01*
X20917D01*
G01X21155D02*
X20917D01*
G01X31886Y155653D02*
X31839Y155927D01*
G01X20193Y157781D02*
X20179Y157861D01*
X20348D01*
G01X21391Y153679D02*
X21155D01*
G01X20821Y157861D02*
X21057D01*
G01X21627Y153679D02*
X21391D01*
G01X21294Y157861D02*
X21532D01*
G01X21057D02*
X21294D01*
G01X20348D02*
X20585D01*
G01D02*
X20821D01*
G01X29681Y153679D02*
X29443D01*
G01Y153451D02*
X29492Y153179D01*
G01D02*
X29540Y152906D01*
G01X29587Y152632D02*
X29636Y152359D01*
G01X24204Y158025D02*
X24232Y157861D01*
X24137D01*
G01X30865Y153679D02*
X30629D01*
G01X31102D02*
X30865D01*
G01X31338D02*
X31102D01*
G01X30154D02*
X29918D01*
G01X30629D02*
X30391D01*
G01D02*
X30154D01*
G01X25015Y153383D02*
X24967Y153657D01*
G01D02*
X24963Y153679D01*
X24944D01*
G01X29918D02*
X29681D01*
G01X28054Y161374D02*
X28103Y161100D01*
G01X28054Y161374D02*
X28007Y161647D01*
G01X28198Y160555D02*
X28247Y160281D01*
G01X28103Y161100D02*
X28151Y160827D01*
G01X28247Y160281D02*
X28294Y160007D01*
G01X28007Y161647D02*
X27958Y161920D01*
G01X28151Y160827D02*
X28198Y160555D01*
G01X31575Y153679D02*
X31338D01*
G01X27894Y162209D02*
X27909Y162202D01*
X27911Y162193D01*
G01X27958Y161920D02*
X27911Y162193D01*
G01X32126Y154287D02*
X32175Y154014D01*
G01X32079Y154560D02*
X32126Y154287D01*
G01X32175Y154014D02*
X32222Y153740D01*
G01X32079Y154560D02*
X32030Y154834D01*
G01X31813Y153679D02*
X31575D01*
G01X28294Y160007D02*
X28342Y159734D01*
G01X32222Y153740D02*
X32233Y153679D01*
X32049D01*
G01D02*
X31813D01*
G01X28438Y159188D02*
X28487Y158914D01*
G01X28391Y159461D02*
X28438Y159188D01*
G01X28342Y159734D02*
X28391Y159461D01*
G01X28582Y158368D02*
X28631Y158095D01*
G01X28875Y157861D02*
X28671D01*
X28631Y158095D01*
G01X28534Y158642D02*
X28582Y158368D01*
G01X28487Y158914D02*
X28534Y158642D01*
G01X23349Y164297D02*
X23804Y164089D01*
G01X23531Y161850D02*
X23483Y162124D01*
G01X23804Y164089D02*
X24257Y163880D01*
G01X29822Y157861D02*
X30059D01*
G01X29584D02*
X29822D01*
G01X24712Y163671D02*
X25168Y163462D01*
G01X24257Y163880D02*
X24712Y163671D01*
G01X23098Y164310D02*
X23079Y164422D01*
X23349Y164297D01*
G01X23435Y162398D02*
X23387Y162671D01*
G01D02*
X23338Y162943D01*
G01X23483Y162124D02*
X23435Y162398D01*
G01X23195Y163764D02*
X23147Y164036D01*
G01X23243Y163490D02*
X23195Y163764D01*
G01X23338Y162943D02*
X23291Y163217D01*
G01D02*
X23243Y163490D01*
G01X23147Y164036D02*
X23098Y164310D01*
G01X26531Y162835D02*
X26987Y162626D01*
G01X25168Y163462D02*
X25622Y163253D01*
G01X31550Y157567D02*
X31502Y157839D01*
G01D02*
X31498Y157861D01*
X31479D01*
G01X27440Y162418D02*
X27894Y162209D01*
G01X26987Y162626D02*
X27440Y162418D01*
G01X31006Y157861D02*
X31243D01*
G01D02*
X31479D01*
G01X30295D02*
X30532D01*
G01X25622Y163253D02*
X26075Y163044D01*
G01X30059Y157861D02*
X30295D01*
G01X24011Y159118D02*
X23964Y159391D01*
G01X31006Y157861D02*
X30770D01*
G01D02*
X30532D01*
G01X26075Y163044D02*
X26531Y162835D01*
G01X23627Y161305D02*
X23580Y161577D01*
G01X23818Y160211D02*
X23771Y160484D01*
G01X23964Y159391D02*
X23915Y159664D01*
G01X23675Y161031D02*
X23627Y161305D01*
G01X23771Y160484D02*
X23724Y160757D01*
G01X23580Y161577D02*
X23531Y161850D01*
G01X23915Y159664D02*
X23867Y159938D01*
G01X23724Y160757D02*
X23675Y161031D01*
G01X23867Y159938D02*
X23818Y160211D01*
G01X20910Y153685D02*
X20917Y153679D01*
G01X20863Y153959D02*
X21155Y153679D01*
G01X20816Y154231D02*
X21391Y153679D01*
G01X20767Y154504D02*
X21627Y153679D01*
G01X20719Y154777D02*
X21864Y153679D01*
G01X20672Y155051D02*
X22101Y153679D01*
G01X20624Y155324D02*
X22337Y153679D01*
G01X20575Y155597D02*
X22575Y153679D01*
G01X20528Y155870D02*
X22812Y153679D01*
G01X20481Y156144D02*
X23049Y153679D01*
G01X20433Y156416D02*
X23285Y153679D01*
G01X20384Y156689D02*
X23521Y153679D01*
G01X20337Y156962D02*
X23759Y153679D01*
G01X20289Y157236D02*
X23996Y153679D01*
G01X20240Y157508D02*
X24234Y153679D01*
G01X20193Y157781D02*
X24470Y153679D01*
G01X20348Y157861D02*
X24707Y153679D01*
G01X24967Y153657D02*
X24944Y153679D01*
G01X20585Y157861D02*
X24944Y153679D01*
G01X23900Y157861D02*
X29636Y152359D01*
G01X24137Y157861D02*
X29587Y152632D01*
G01X29540Y152906D02*
X24204Y158025D01*
G01X24155Y158298D02*
X29492Y153179D01*
G01X24107Y158571D02*
X29443Y153451D01*
G01Y153679D02*
X24060Y158844D01*
G01X29681Y153679D02*
X24011Y159118D01*
G01X29918Y153679D02*
X23964Y159391D01*
G01X30154Y153679D02*
X23915Y159664D01*
G01X30391Y153679D02*
X23867Y159938D01*
G01X30629Y153679D02*
X23818Y160211D01*
G01X30865Y153679D02*
X23771Y160484D01*
G01X31102Y153679D02*
X23724Y160757D01*
G01X31338Y153679D02*
X23675Y161031D01*
G01X31575Y153679D02*
X23627Y161305D01*
G01X31813Y153679D02*
X23580Y161577D01*
G01X32049Y153679D02*
X23531Y161850D01*
G01X32222Y153740D02*
X23483Y162124D01*
G01X23435Y162398D02*
X32175Y154014D01*
G01X23387Y162671D02*
X32126Y154287D01*
G01X23338Y162943D02*
X32079Y154560D01*
G01X23291Y163217D02*
X28631Y158095D01*
G01X32030Y154834D02*
X28875Y157861D01*
G01X23243Y163490D02*
X28582Y158368D01*
G01X31982Y155107D02*
X29111Y157861D01*
G01X23195Y163764D02*
X28534Y158642D01*
G01X31935Y155380D02*
X29348Y157861D01*
G01X31886Y155653D02*
X29584Y157861D01*
G01X23147Y164036D02*
X28487Y158914D01*
G01X23098Y164310D02*
X28438Y159188D01*
G01X31839Y155927D02*
X29822Y157861D01*
G01X31790Y156200D02*
X30059Y157861D01*
G01X23349Y164297D02*
X28391Y159461D01*
G01X23804Y164089D02*
X28342Y159734D01*
G01X31742Y156473D02*
X30295Y157861D01*
G01X24257Y163880D02*
X28294Y160007D01*
G01X31693Y156746D02*
X30532Y157861D01*
G01X30770D02*
X31646Y157020D01*
G01X24712Y163671D02*
X28247Y160281D01*
G01X25168Y163462D02*
X28198Y160555D01*
G01X31598Y157293D02*
X31006Y157861D01*
G01X31550Y157567D02*
X31243Y157861D01*
G01X25622Y163253D02*
X28151Y160827D01*
G01X31502Y157839D02*
X31479Y157861D01*
G01X26075Y163044D02*
X28103Y161100D01*
G01X26531Y162835D02*
X28054Y161374D01*
G01X26987Y162626D02*
X28007Y161647D01*
G01X27440Y162418D02*
X27958Y161920D01*
G01X27894Y162209D02*
X27911Y162193D01*
G01X25159Y152564D02*
X25111Y152836D01*
G01X31935Y155380D02*
X31886Y155653D01*
G01X25111Y152836D02*
X25064Y153110D01*
G01X31598Y157293D02*
X31550Y157567D01*
G01X31646Y157020D02*
X31693Y156746D01*
G01X29443Y153679D02*
X29404D01*
X29443Y153451D01*
G01X31598Y157293D02*
X31646Y157020D01*
G01X25064Y153110D02*
X25015Y153383D01*
G01X31839Y155927D02*
X31790Y156200D01*
G01X25207Y152290D02*
X25159Y152564D01*
G01X31742Y156473D02*
X31693Y156746D01*
G01X31790Y156200D02*
X31742Y156473D01*
G01X29540Y152906D02*
X29587Y152632D01*
G01X29348Y157861D02*
X29584D01*
G01X29111D02*
X29348D01*
G01X20910Y153685D02*
X20863Y153959D01*
G01X31982Y155107D02*
X31935Y155380D01*
G01X28875Y157861D02*
X29111D01*
G01X32030Y154834D02*
X31982Y155107D01*
G01X20481Y156144D02*
X20433Y156416D01*
G01D02*
X20384Y156689D01*
G01X22812Y153679D02*
X22575D01*
G01X23049D02*
X22812D01*
G01X20575Y155597D02*
X20528Y155870D01*
G01X23285Y153679D02*
X23521D01*
G01X20624Y155324D02*
X20575Y155597D01*
G01X23285Y153679D02*
X23049D01*
G01X22575D02*
X22337D01*
G01X20528Y155870D02*
X20481Y156144D01*
G01X20289Y157236D02*
X20240Y157508D01*
G01X21864Y153679D02*
X21627D01*
G01X22337D02*
X22101D01*
G01D02*
X21864D01*
G01X23521D02*
X23759D01*
G01X20337Y156962D02*
X20289Y157236D01*
G01X20863Y153959D02*
X20816Y154231D01*
G01X20672Y155051D02*
X20624Y155324D01*
G01X23996Y153679D02*
X24234D01*
G01X20767Y154504D02*
X20719Y154777D01*
G01D02*
X20672Y155051D01*
G01X23759Y153679D02*
X23996D01*
G01X24234D02*
X24470D01*
G01X20240Y157508D02*
X20193Y157781D01*
G01X24707Y153679D02*
X24944D01*
G01X20816Y154231D02*
X20767Y154504D01*
G01X24470Y153679D02*
X24707D01*
G01X20384Y156689D02*
X20337Y156962D01*
G01X22953Y157861D02*
X23189D01*
G01X22716D02*
X22953D01*
G01X22242D02*
X22480D01*
G01D02*
X22716D01*
G01X21769D02*
X22005D01*
G01D02*
X22242D01*
G01X23664D02*
X23900D01*
G01X24107Y158571D02*
X24060Y158844D01*
G01D02*
X24011Y159118D01*
G01X21532Y157861D02*
X21769D01*
G01X23189D02*
X23427D01*
G01D02*
X23664D01*
G01X24204Y158025D02*
X24155Y158298D01*
G01D02*
X24107Y158571D01*
G01X23900Y157861D02*
X24137D01*
G01X20910Y153685D02*
X20912Y153679D01*
X20917D01*
G01X21155D02*
X20917D01*
G01X31886Y155653D02*
X31839Y155927D01*
G01X20193Y157781D02*
X20179Y157861D01*
X20348D01*
G01X21391Y153679D02*
X21155D01*
G01X20821Y157861D02*
X21057D01*
G01X21627Y153679D02*
X21391D01*
G01X21294Y157861D02*
X21532D01*
G01X21057D02*
X21294D01*
G01X20348D02*
X20585D01*
G01D02*
X20821D01*
G01X29681Y153679D02*
X29443D01*
G01Y153451D02*
X29492Y153179D01*
G01D02*
X29540Y152906D01*
G01X29587Y152632D02*
X29636Y152359D01*
G01X24204Y158025D02*
X24232Y157861D01*
X24137D01*
G01X30865Y153679D02*
X30629D01*
G01X31102D02*
X30865D01*
G01X31338D02*
X31102D01*
G01X30154D02*
X29918D01*
G01X30629D02*
X30391D01*
G01D02*
X30154D01*
G01X25015Y153383D02*
X24967Y153657D01*
G01D02*
X24963Y153679D01*
X24944D01*
G01X29918D02*
X29681D01*
G01X28054Y161374D02*
X28103Y161100D01*
G01X28054Y161374D02*
X28007Y161647D01*
G01X28198Y160555D02*
X28247Y160281D01*
G01X28103Y161100D02*
X28151Y160827D01*
G01X28247Y160281D02*
X28294Y160007D01*
G01X28007Y161647D02*
X27958Y161920D01*
G01X28151Y160827D02*
X28198Y160555D01*
G01X31575Y153679D02*
X31338D01*
G01X27894Y162209D02*
X27909Y162202D01*
X27911Y162193D01*
G01X27958Y161920D02*
X27911Y162193D01*
G01X32126Y154287D02*
X32175Y154014D01*
G01X32079Y154560D02*
X32126Y154287D01*
G01X32175Y154014D02*
X32222Y153740D01*
G01X32079Y154560D02*
X32030Y154834D01*
G01X31813Y153679D02*
X31575D01*
G01X28294Y160007D02*
X28342Y159734D01*
G01X32222Y153740D02*
X32233Y153679D01*
X32049D01*
G01D02*
X31813D01*
G01X28438Y159188D02*
X28487Y158914D01*
G01X28391Y159461D02*
X28438Y159188D01*
G01X28342Y159734D02*
X28391Y159461D01*
G01X28582Y158368D02*
X28631Y158095D01*
G01X28875Y157861D02*
X28671D01*
X28631Y158095D01*
G01X28534Y158642D02*
X28582Y158368D01*
G01X28487Y158914D02*
X28534Y158642D01*
G01X23349Y164297D02*
X23804Y164089D01*
G01X23531Y161850D02*
X23483Y162124D01*
G01X23804Y164089D02*
X24257Y163880D01*
G01X29822Y157861D02*
X30059D01*
G01X29584D02*
X29822D01*
G01X24712Y163671D02*
X25168Y163462D01*
G01X24257Y163880D02*
X24712Y163671D01*
G01X23098Y164310D02*
X23079Y164422D01*
X23349Y164297D01*
G01X23435Y162398D02*
X23387Y162671D01*
G01D02*
X23338Y162943D01*
G01X23483Y162124D02*
X23435Y162398D01*
G01X23195Y163764D02*
X23147Y164036D01*
G01X23243Y163490D02*
X23195Y163764D01*
G01X23338Y162943D02*
X23291Y163217D01*
G01D02*
X23243Y163490D01*
G01X23147Y164036D02*
X23098Y164310D01*
G01X26531Y162835D02*
X26987Y162626D01*
G01X25168Y163462D02*
X25622Y163253D01*
G01X31550Y157567D02*
X31502Y157839D01*
G01D02*
X31498Y157861D01*
X31479D01*
G01X27440Y162418D02*
X27894Y162209D01*
G01X26987Y162626D02*
X27440Y162418D01*
G01X31006Y157861D02*
X31243D01*
G01D02*
X31479D01*
G01X30295D02*
X30532D01*
G01X25622Y163253D02*
X26075Y163044D01*
G01X30059Y157861D02*
X30295D01*
G01X24011Y159118D02*
X23964Y159391D01*
G01X31006Y157861D02*
X30770D01*
G01D02*
X30532D01*
G01X26075Y163044D02*
X26531Y162835D01*
G01X23627Y161305D02*
X23580Y161577D01*
G01X23818Y160211D02*
X23771Y160484D01*
G01X23964Y159391D02*
X23915Y159664D01*
G01X23675Y161031D02*
X23627Y161305D01*
G01X23771Y160484D02*
X23724Y160757D01*
G01X23580Y161577D02*
X23531Y161850D01*
G01X23915Y159664D02*
X23867Y159938D01*
G01X23724Y160757D02*
X23675Y161031D01*
G01X23867Y159938D02*
X23818Y160211D01*
G01X46712Y140976D02*
X46650Y141037D01*
G01X46949Y140976D02*
X46602Y141310D01*
G01X47187Y140976D02*
X46555Y141582D01*
G01X47423Y140976D02*
X46506Y141856D01*
G01X47660Y140976D02*
X46457Y142130D01*
G01X47898Y140976D02*
X46410Y142403D01*
G01X48134Y140976D02*
X46362Y142676D01*
G01X48371Y140976D02*
X46313Y142949D01*
G01X48608Y140976D02*
X46265Y143223D01*
G01X48844Y140976D02*
X46217Y143496D01*
G01X49080Y140976D02*
X46170Y143769D01*
G01X49319Y140976D02*
X46121Y144043D01*
G01X49555Y140976D02*
X46073Y144317D01*
G01X49791Y140976D02*
X46026Y144589D01*
G01X50028Y140976D02*
X45977Y144862D01*
G01X50266Y140976D02*
X45928Y145136D01*
G01X50503Y140976D02*
X45881Y145410D01*
G01X50739Y140976D02*
X45833Y145683D01*
G01X50976Y140976D02*
X45784Y145956D01*
G01X51075Y141107D02*
X45736Y146230D01*
G01X51028Y141381D02*
X45688Y146503D01*
G01X50979Y141654D02*
X45641Y146776D01*
G01X50932Y141927D02*
X45592Y147049D01*
G01X50884Y142201D02*
X45544Y147323D01*
G01X50835Y142475D02*
X45497Y147596D01*
G01X50788Y142747D02*
X45448Y147869D01*
G01X50740Y143020D02*
X45399Y148143D01*
G01X50692Y143294D02*
X45352Y148416D01*
G01X50643Y143567D02*
X45304Y148690D01*
G01X50597Y143840D02*
X45255Y148963D01*
G01X45208Y149236D02*
X50548Y144113D01*
G01X45160Y149509D02*
X50499Y144386D01*
G01X45112Y149783D02*
X50452Y144660D01*
G01X45063Y150056D02*
X50404Y144933D01*
G01X45009Y150336D02*
X50355Y145206D01*
G01X44943Y150626D02*
X50308Y145480D01*
G01X44878Y150915D02*
X50260Y145753D01*
G01X44815Y151203D02*
X50211Y146026D01*
G01X44697Y151543D02*
X50164Y146299D01*
G01X44577Y151886D02*
X50117Y146572D01*
G01X44387Y152295D02*
X50068Y146846D01*
G01X44073Y152824D02*
X50020Y147119D01*
G01X38778Y158131D02*
X49973Y147391D01*
G01X38995Y158151D02*
X49924Y147665D01*
G01X39210Y158170D02*
X49876Y147939D01*
G01X39426Y158191D02*
X49829Y148211D01*
G01X39643Y158210D02*
X49780Y148485D01*
G01X46457Y142130D02*
X46506Y141856D01*
G01X46217Y143496D02*
X46170Y143769D01*
G01X46362Y142676D02*
X46410Y142403D01*
G01X46506Y141856D02*
X46555Y141582D01*
G01X46410Y142403D02*
X46457Y142130D01*
G01X45977Y144862D02*
X45928Y145136D01*
G01X46265Y143223D02*
X46313Y142949D01*
G01X46026Y144589D02*
X45977Y144862D01*
G01X45833Y145683D02*
X45784Y145956D01*
G01X45881Y145410D02*
X45833Y145683D01*
G01X45928Y145136D02*
X45881Y145410D01*
G01X46170Y143769D02*
X46121Y144043D01*
G01X46217Y143496D02*
X46265Y143223D01*
G01X46073Y144317D02*
X46026Y144589D01*
G01X46121Y144043D02*
X46073Y144317D01*
G01X45544Y147323D02*
X45497Y147596D01*
G01X46313Y142949D02*
X46362Y142676D01*
G01X45497Y147596D02*
X45448Y147869D01*
G01X45399Y148143D02*
X45352Y148416D01*
G01X45448Y147869D02*
X45399Y148143D01*
G01X45641Y146776D02*
X45592Y147049D01*
G01X45736Y146230D02*
X45688Y146503D01*
G01X45784Y145956D02*
X45736Y146230D01*
G01X45592Y147049D02*
X45544Y147323D01*
G01X45688Y146503D02*
X45641Y146776D01*
G01X45352Y148416D02*
X45304Y148690D01*
G01X46949Y140976D02*
X46712D01*
G01X47423D02*
X47187D01*
G01D02*
X46949D01*
G01X47660D02*
X47423D01*
G01X47898D02*
X47660D01*
G01X48134D02*
X47898D01*
G01X46602Y141310D02*
X46650Y141037D01*
G01X46555Y141582D02*
X46602Y141310D01*
G01X46712Y140976D02*
X46661D01*
X46650Y141037D01*
G01X46712Y140976D02*
X46650Y141037D01*
G01X46949Y140976D02*
X46602Y141310D01*
G01X47187Y140976D02*
X46555Y141582D01*
G01X47423Y140976D02*
X46506Y141856D01*
G01X47660Y140976D02*
X46457Y142130D01*
G01X47898Y140976D02*
X46410Y142403D01*
G01X48134Y140976D02*
X46362Y142676D01*
G01X48371Y140976D02*
X46313Y142949D01*
G01X48608Y140976D02*
X46265Y143223D01*
G01X48844Y140976D02*
X46217Y143496D01*
G01X49080Y140976D02*
X46170Y143769D01*
G01X49319Y140976D02*
X46121Y144043D01*
G01X49555Y140976D02*
X46073Y144317D01*
G01X49791Y140976D02*
X46026Y144589D01*
G01X50028Y140976D02*
X45977Y144862D01*
G01X50266Y140976D02*
X45928Y145136D01*
G01X50503Y140976D02*
X45881Y145410D01*
G01X50739Y140976D02*
X45833Y145683D01*
G01X50976Y140976D02*
X45784Y145956D01*
G01X51075Y141107D02*
X45736Y146230D01*
G01X51028Y141381D02*
X45688Y146503D01*
G01X50979Y141654D02*
X45641Y146776D01*
G01X50932Y141927D02*
X45592Y147049D01*
G01X50884Y142201D02*
X45544Y147323D01*
G01X50835Y142475D02*
X45497Y147596D01*
G01X50788Y142747D02*
X45448Y147869D01*
G01X50740Y143020D02*
X45399Y148143D01*
G01X50692Y143294D02*
X45352Y148416D01*
G01X50643Y143567D02*
X45304Y148690D01*
G01X50597Y143840D02*
X45255Y148963D01*
G01X45208Y149236D02*
X50548Y144113D01*
G01X45160Y149509D02*
X50499Y144386D01*
G01X45112Y149783D02*
X50452Y144660D01*
G01X45063Y150056D02*
X50404Y144933D01*
G01X45009Y150336D02*
X50355Y145206D01*
G01X44943Y150626D02*
X50308Y145480D01*
G01X44878Y150915D02*
X50260Y145753D01*
G01X44815Y151203D02*
X50211Y146026D01*
G01X44697Y151543D02*
X50164Y146299D01*
G01X44577Y151886D02*
X50117Y146572D01*
G01X44387Y152295D02*
X50068Y146846D01*
G01X44073Y152824D02*
X50020Y147119D01*
G01X38778Y158131D02*
X49973Y147391D01*
G01X38995Y158151D02*
X49924Y147665D01*
G01X39210Y158170D02*
X49876Y147939D01*
G01X39426Y158191D02*
X49829Y148211D01*
G01X39643Y158210D02*
X49780Y148485D01*
G01X46457Y142130D02*
X46506Y141856D01*
G01X46217Y143496D02*
X46170Y143769D01*
G01X46362Y142676D02*
X46410Y142403D01*
G01X46506Y141856D02*
X46555Y141582D01*
G01X46410Y142403D02*
X46457Y142130D01*
G01X45977Y144862D02*
X45928Y145136D01*
G01X46265Y143223D02*
X46313Y142949D01*
G01X46026Y144589D02*
X45977Y144862D01*
G01X45833Y145683D02*
X45784Y145956D01*
G01X45881Y145410D02*
X45833Y145683D01*
G01X45928Y145136D02*
X45881Y145410D01*
G01X46170Y143769D02*
X46121Y144043D01*
G01X46217Y143496D02*
X46265Y143223D01*
G01X46073Y144317D02*
X46026Y144589D01*
G01X46121Y144043D02*
X46073Y144317D01*
G01X45544Y147323D02*
X45497Y147596D01*
G01X46313Y142949D02*
X46362Y142676D01*
G01X45497Y147596D02*
X45448Y147869D01*
G01X45399Y148143D02*
X45352Y148416D01*
G01X45448Y147869D02*
X45399Y148143D01*
G01X45641Y146776D02*
X45592Y147049D01*
G01X45736Y146230D02*
X45688Y146503D01*
G01X45784Y145956D02*
X45736Y146230D01*
G01X45592Y147049D02*
X45544Y147323D01*
G01X45688Y146503D02*
X45641Y146776D01*
G01X45352Y148416D02*
X45304Y148690D01*
G01X46949Y140976D02*
X46712D01*
G01X47423D02*
X47187D01*
G01D02*
X46949D01*
G01X47660D02*
X47423D01*
G01X47898D02*
X47660D01*
G01X48134D02*
X47898D01*
G01X46602Y141310D02*
X46650Y141037D01*
G01X46555Y141582D02*
X46602Y141310D01*
G01X46712Y140976D02*
X46661D01*
X46650Y141037D01*
G01X39897Y158193D02*
X49733Y148758D01*
G01X40158Y158170D02*
X49685Y149031D01*
G01X40421Y158145D02*
X49636Y149304D01*
G01X40682Y158121D02*
X49589Y149577D01*
G01X40945Y158097D02*
X49541Y149851D01*
G01X41276Y158007D02*
X49493Y150124D01*
G01X41608Y157915D02*
X49445Y150397D01*
G01X41941Y157822D02*
X49398Y150670D01*
G01X45255Y148963D02*
X45304Y148690D01*
G01X45208Y149236D02*
X45255Y148963D01*
G01X45160Y149509D02*
X45208Y149236D01*
G01X45112Y149783D02*
X45160Y149509D01*
G01X45063Y150056D02*
X45112Y149783D01*
G01X39897Y158193D02*
X49733Y148758D01*
G01X40158Y158170D02*
X49685Y149031D01*
G01X40421Y158145D02*
X49636Y149304D01*
G01X40682Y158121D02*
X49589Y149577D01*
G01X40945Y158097D02*
X49541Y149851D01*
G01X41276Y158007D02*
X49493Y150124D01*
G01X41608Y157915D02*
X49445Y150397D01*
G01X41941Y157822D02*
X49398Y150670D01*
G01X45255Y148963D02*
X45304Y148690D01*
G01X45208Y149236D02*
X45255Y148963D01*
G01X45160Y149509D02*
X45208Y149236D01*
G01X45112Y149783D02*
X45160Y149509D01*
G01X45063Y150056D02*
X45112Y149783D01*
G01X36529Y140976D02*
X36453Y141048D01*
G01X36765Y140976D02*
X36404Y141322D01*
G01X37001Y140976D02*
X36356Y141595D01*
G01X37239Y140976D02*
X36309Y141868D01*
G01X37475Y140976D02*
X36260Y142141D01*
G01X37711Y140976D02*
X36213Y142414D01*
G01X37949Y140976D02*
X36165Y142688D01*
G01X38186Y140976D02*
X36116Y142962D01*
G01X38422Y140976D02*
X36069Y143234D01*
G01X38660Y140976D02*
X36021Y143507D01*
G01X38897Y140976D02*
X35973Y143781D01*
G01X39133Y140976D02*
X35925Y144054D01*
G01X39370Y140976D02*
X35878Y144327D01*
G01X39608Y140976D02*
X35829Y144600D01*
G01X39844Y140976D02*
X35781Y144873D01*
G01X40081Y140976D02*
X35734Y145147D01*
G01X40318Y140976D02*
X35685Y145419D01*
G01X40554Y140976D02*
X35638Y145693D01*
G01X40792Y140976D02*
X35590Y145966D01*
G01X40883Y141116D02*
X35541Y146240D01*
G01X40834Y141389D02*
X35494Y146512D01*
G01X40786Y141662D02*
X35446Y146785D01*
G01X40739Y141936D02*
X35398Y147058D01*
G01X40690Y142209D02*
X35350Y147332D01*
G01X40642Y142482D02*
X35303Y147605D01*
G01X40595Y142755D02*
X35254Y147878D01*
G01X40546Y143029D02*
X35206Y148152D01*
G01X40497Y143303D02*
X35159Y148425D01*
G01X40450Y143575D02*
X35110Y148698D01*
G01X40402Y143849D02*
X35063Y148971D01*
G01X40354Y144122D02*
X35015Y149244D01*
G01X40306Y144396D02*
X34966Y149518D01*
G01X40259Y144669D02*
X34919Y149791D01*
G01X40210Y144942D02*
X34871Y150063D01*
G01X40161Y145215D02*
X34822Y150337D01*
G01X40114Y145488D02*
X34782Y150604D01*
G01X40066Y145762D02*
X34751Y150861D01*
G01X40017Y146035D02*
X34719Y151117D01*
G01X39970Y146308D02*
X34688Y151375D01*
G01X39922Y146582D02*
X34657Y151633D01*
G01X39873Y146855D02*
X34624Y151890D01*
G01X39826Y147128D02*
X34595Y152147D01*
G01X39779Y147402D02*
X34589Y152379D01*
G01X34592Y152604D02*
X39730Y147675D01*
G01X39681Y147948D02*
X34593Y152830D01*
G01X39633Y148221D02*
X34595Y153055D01*
G01X39586Y148495D02*
X34597Y153281D01*
G01X39133Y140976D02*
X38897D01*
G01X38422D02*
X38186D01*
G01X38660D02*
X38422D01*
G01X38897D02*
X38660D01*
G01X38186D02*
X37949D01*
G01D02*
X37711D01*
G01D02*
X37475D01*
G01X40834Y141389D02*
X40883Y141116D01*
G01X40786Y141662D02*
X40834Y141389D01*
G01X40792Y140976D02*
X40554D01*
G01D02*
X40318D01*
G01X40739Y141936D02*
X40786Y141662D01*
G01X40883Y141116D02*
X40907Y140976D01*
X40792D01*
G01X40642Y142482D02*
X40690Y142209D01*
G01D02*
X40739Y141936D01*
G01X39370Y140976D02*
X39133D01*
G01X40318D02*
X40081D01*
G01X39608D02*
X39370D01*
G01X40081D02*
X39844D01*
G01D02*
X39608D01*
G01X40595Y142755D02*
X40642Y142482D01*
G01X40259Y144669D02*
X40306Y144396D01*
G01X39826Y147128D02*
X39873Y146855D01*
G01D02*
X39922Y146582D01*
G01X40017Y146035D02*
X40066Y145762D01*
G01X39970Y146308D02*
X40017Y146035D01*
G01X39922Y146582D02*
X39970Y146308D01*
G01X40354Y144122D02*
X40402Y143849D01*
G01D02*
X40450Y143575D01*
G01X40066Y145762D02*
X40114Y145488D01*
G01X40450Y143575D02*
X40497Y143303D01*
G01D02*
X40546Y143029D01*
G01X40114Y145488D02*
X40161Y145215D01*
G01D02*
X40210Y144942D01*
G01X40546Y143029D02*
X40595Y142755D01*
G01X40306Y144396D02*
X40354Y144122D01*
G01X40210Y144942D02*
X40259Y144669D01*
G01X39779Y147402D02*
X39826Y147128D01*
G01X39537Y148768D02*
X39586Y148495D01*
G01X39681Y147948D02*
X39730Y147675D01*
G01X39586Y148495D02*
X39633Y148221D01*
G01X36260Y142141D02*
X36309Y141868D01*
G01X36356Y141595D02*
X36404Y141322D01*
G01X35734Y145147D02*
X35781Y144873D01*
G01X36309Y141868D02*
X36356Y141595D01*
G01X35685Y145419D02*
X35734Y145147D01*
G01X35590Y145966D02*
X35638Y145693D01*
G01X36404Y141322D02*
X36453Y141048D01*
G01X35541Y146240D02*
X35590Y145966D01*
G01X35638Y145693D02*
X35685Y145419D01*
G01X36529Y140976D02*
X36465D01*
X36453Y141048D01*
G01X36021Y143507D02*
X36069Y143234D01*
G01X35925Y144054D02*
X35973Y143781D01*
G01D02*
X36021Y143507D01*
G01X35878Y144327D02*
X35925Y144054D01*
G01X35829Y144600D02*
X35878Y144327D01*
G01X36165Y142688D02*
X36213Y142414D01*
G01X35781Y144873D02*
X35829Y144600D01*
G01X36213Y142414D02*
X36260Y142141D01*
G01X36116Y142962D02*
X36165Y142688D01*
G01X36069Y143234D02*
X36116Y142962D01*
G01X35206Y148152D02*
X35254Y147878D01*
G01X35110Y148698D02*
X35159Y148425D01*
G01X35494Y146512D02*
X35541Y146240D01*
G01X37239Y140976D02*
X37001D01*
G01X37475D02*
X37239D01*
G01X37001D02*
X36765D01*
G01X35350Y147332D02*
X35398Y147058D01*
G01X35303Y147605D02*
X35350Y147332D01*
G01X35398Y147058D02*
X35446Y146785D01*
G01D02*
X35494Y146512D01*
G01X36765Y140976D02*
X36529D01*
G01X35159Y148425D02*
X35206Y148152D01*
G01X35254Y147878D02*
X35303Y147605D01*
G01X39779Y147402D02*
X39730Y147675D01*
G01X39633Y148221D02*
X39681Y147948D01*
G01X36529Y140976D02*
X36453Y141048D01*
G01X36765Y140976D02*
X36404Y141322D01*
G01X37001Y140976D02*
X36356Y141595D01*
G01X37239Y140976D02*
X36309Y141868D01*
G01X37475Y140976D02*
X36260Y142141D01*
G01X37711Y140976D02*
X36213Y142414D01*
G01X37949Y140976D02*
X36165Y142688D01*
G01X38186Y140976D02*
X36116Y142962D01*
G01X38422Y140976D02*
X36069Y143234D01*
G01X38660Y140976D02*
X36021Y143507D01*
G01X38897Y140976D02*
X35973Y143781D01*
G01X39133Y140976D02*
X35925Y144054D01*
G01X39370Y140976D02*
X35878Y144327D01*
G01X39608Y140976D02*
X35829Y144600D01*
G01X39844Y140976D02*
X35781Y144873D01*
G01X40081Y140976D02*
X35734Y145147D01*
G01X40318Y140976D02*
X35685Y145419D01*
G01X40554Y140976D02*
X35638Y145693D01*
G01X40792Y140976D02*
X35590Y145966D01*
G01X40883Y141116D02*
X35541Y146240D01*
G01X40834Y141389D02*
X35494Y146512D01*
G01X40786Y141662D02*
X35446Y146785D01*
G01X40739Y141936D02*
X35398Y147058D01*
G01X40690Y142209D02*
X35350Y147332D01*
G01X40642Y142482D02*
X35303Y147605D01*
G01X40595Y142755D02*
X35254Y147878D01*
G01X40546Y143029D02*
X35206Y148152D01*
G01X40497Y143303D02*
X35159Y148425D01*
G01X40450Y143575D02*
X35110Y148698D01*
G01X40402Y143849D02*
X35063Y148971D01*
G01X40354Y144122D02*
X35015Y149244D01*
G01X40306Y144396D02*
X34966Y149518D01*
G01X40259Y144669D02*
X34919Y149791D01*
G01X40210Y144942D02*
X34871Y150063D01*
G01X40161Y145215D02*
X34822Y150337D01*
G01X40114Y145488D02*
X34782Y150604D01*
G01X40066Y145762D02*
X34751Y150861D01*
G01X40017Y146035D02*
X34719Y151117D01*
G01X39970Y146308D02*
X34688Y151375D01*
G01X39922Y146582D02*
X34657Y151633D01*
G01X39873Y146855D02*
X34624Y151890D01*
G01X39826Y147128D02*
X34595Y152147D01*
G01X39779Y147402D02*
X34589Y152379D01*
G01X34592Y152604D02*
X39730Y147675D01*
G01X39681Y147948D02*
X34593Y152830D01*
G01X39633Y148221D02*
X34595Y153055D01*
G01X39586Y148495D02*
X34597Y153281D01*
G01X39133Y140976D02*
X38897D01*
G01X38422D02*
X38186D01*
G01X38660D02*
X38422D01*
G01X38897D02*
X38660D01*
G01X38186D02*
X37949D01*
G01D02*
X37711D01*
G01D02*
X37475D01*
G01X40834Y141389D02*
X40883Y141116D01*
G01X40786Y141662D02*
X40834Y141389D01*
G01X40792Y140976D02*
X40554D01*
G01D02*
X40318D01*
G01X40739Y141936D02*
X40786Y141662D01*
G01X40883Y141116D02*
X40907Y140976D01*
X40792D01*
G01X40642Y142482D02*
X40690Y142209D01*
G01D02*
X40739Y141936D01*
G01X39370Y140976D02*
X39133D01*
G01X40318D02*
X40081D01*
G01X39608D02*
X39370D01*
G01X40081D02*
X39844D01*
G01D02*
X39608D01*
G01X40595Y142755D02*
X40642Y142482D01*
G01X40259Y144669D02*
X40306Y144396D01*
G01X39826Y147128D02*
X39873Y146855D01*
G01D02*
X39922Y146582D01*
G01X40017Y146035D02*
X40066Y145762D01*
G01X39970Y146308D02*
X40017Y146035D01*
G01X39922Y146582D02*
X39970Y146308D01*
G01X40354Y144122D02*
X40402Y143849D01*
G01D02*
X40450Y143575D01*
G01X40066Y145762D02*
X40114Y145488D01*
G01X40450Y143575D02*
X40497Y143303D01*
G01D02*
X40546Y143029D01*
G01X40114Y145488D02*
X40161Y145215D01*
G01D02*
X40210Y144942D01*
G01X40546Y143029D02*
X40595Y142755D01*
G01X40306Y144396D02*
X40354Y144122D01*
G01X40210Y144942D02*
X40259Y144669D01*
G01X39779Y147402D02*
X39826Y147128D01*
G01X39537Y148768D02*
X39586Y148495D01*
G01X39681Y147948D02*
X39730Y147675D01*
G01X39586Y148495D02*
X39633Y148221D01*
G01X36260Y142141D02*
X36309Y141868D01*
G01X36356Y141595D02*
X36404Y141322D01*
G01X35734Y145147D02*
X35781Y144873D01*
G01X36309Y141868D02*
X36356Y141595D01*
G01X35685Y145419D02*
X35734Y145147D01*
G01X35590Y145966D02*
X35638Y145693D01*
G01X36404Y141322D02*
X36453Y141048D01*
G01X35541Y146240D02*
X35590Y145966D01*
G01X35638Y145693D02*
X35685Y145419D01*
G01X36529Y140976D02*
X36465D01*
X36453Y141048D01*
G01X36021Y143507D02*
X36069Y143234D01*
G01X35925Y144054D02*
X35973Y143781D01*
G01D02*
X36021Y143507D01*
G01X35878Y144327D02*
X35925Y144054D01*
G01X35829Y144600D02*
X35878Y144327D01*
G01X36165Y142688D02*
X36213Y142414D01*
G01X35781Y144873D02*
X35829Y144600D01*
G01X36213Y142414D02*
X36260Y142141D01*
G01X36116Y142962D02*
X36165Y142688D01*
G01X36069Y143234D02*
X36116Y142962D01*
G01X35206Y148152D02*
X35254Y147878D01*
G01X35110Y148698D02*
X35159Y148425D01*
G01X35494Y146512D02*
X35541Y146240D01*
G01X37239Y140976D02*
X37001D01*
G01X37475D02*
X37239D01*
G01X37001D02*
X36765D01*
G01X35350Y147332D02*
X35398Y147058D01*
G01X35303Y147605D02*
X35350Y147332D01*
G01X35398Y147058D02*
X35446Y146785D01*
G01D02*
X35494Y146512D01*
G01X36765Y140976D02*
X36529D01*
G01X35159Y148425D02*
X35206Y148152D01*
G01X35254Y147878D02*
X35303Y147605D01*
G01X39779Y147402D02*
X39730Y147675D01*
G01X39633Y148221D02*
X39681Y147948D01*
G01X39537Y148768D02*
X34597Y153506D01*
G01X39490Y149041D02*
X34603Y153728D01*
G01X39442Y149314D02*
X34638Y153922D01*
G01X39393Y149588D02*
X34673Y154116D01*
G01X34709Y154310D02*
X39344Y149861D01*
G01X34742Y154503D02*
X39298Y150133D01*
G01X34778Y154697D02*
X39266Y150392D01*
G01X34812Y154891D02*
X39231Y150652D01*
G01X34858Y155076D02*
X39198Y150912D01*
G01X34926Y155237D02*
X39167Y151168D01*
G01X34993Y155399D02*
X39165Y151397D01*
G01X35063Y155560D02*
X39163Y151627D01*
G01X35132Y155722D02*
X39160Y151856D01*
G01X35200Y155883D02*
X39171Y152073D01*
G01X39344Y149861D02*
X39393Y149588D01*
G01X34919Y149791D02*
X34966Y149518D01*
G01X34871Y150063D02*
X34919Y149791D01*
G01X39393Y149588D02*
X39442Y149314D01*
G01X35015Y149244D02*
X35063Y148971D01*
G01D02*
X35110Y148698D01*
G01X34966Y149518D02*
X35015Y149244D01*
G01X39490Y149041D02*
X39537Y148768D01*
G01X34822Y150337D02*
X34871Y150063D01*
G01X39442Y149314D02*
X39490Y149041D01*
G01X39537Y148768D02*
X34597Y153506D01*
G01X39490Y149041D02*
X34603Y153728D01*
G01X39442Y149314D02*
X34638Y153922D01*
G01X39393Y149588D02*
X34673Y154116D01*
G01X34709Y154310D02*
X39344Y149861D01*
G01X34742Y154503D02*
X39298Y150133D01*
G01X34778Y154697D02*
X39266Y150392D01*
G01X34812Y154891D02*
X39231Y150652D01*
G01X34858Y155076D02*
X39198Y150912D01*
G01X34926Y155237D02*
X39167Y151168D01*
G01X34993Y155399D02*
X39165Y151397D01*
G01X35063Y155560D02*
X39163Y151627D01*
G01X35132Y155722D02*
X39160Y151856D01*
G01X35200Y155883D02*
X39171Y152073D01*
G01X39344Y149861D02*
X39393Y149588D01*
G01X34919Y149791D02*
X34966Y149518D01*
G01X34871Y150063D02*
X34919Y149791D01*
G01X39393Y149588D02*
X39442Y149314D01*
G01X35015Y149244D02*
X35063Y148971D01*
G01D02*
X35110Y148698D01*
G01X34966Y149518D02*
X35015Y149244D01*
G01X39490Y149041D02*
X39537Y148768D01*
G01X34822Y150337D02*
X34871Y150063D01*
G01X39442Y149314D02*
X39490Y149041D01*
G01X38346Y158091D02*
X42802Y153816D01*
G01X38562Y158111D02*
X43264Y153600D01*
G01X42342Y157665D02*
X49349Y150944D01*
G01X42813Y157442D02*
X49301Y151217D01*
G01X43462Y157045D02*
X49254Y151490D01*
G01X43869Y156882D02*
X49205Y151763D01*
G01X43820Y157156D02*
X49156Y152037D01*
G01X43773Y157429D02*
X49110Y152310D01*
G01X43725Y157702D02*
X49061Y152583D01*
G01X43796Y157861D02*
X49012Y152856D01*
G01X44033Y157861D02*
X48966Y153129D01*
G01X44271Y157861D02*
X48918Y153403D01*
G01X44507Y157861D02*
X48869Y153676D01*
G01X44743Y157861D02*
X48821Y153949D01*
G01X44980Y157861D02*
X48774Y154222D01*
G01X45217Y157861D02*
X48725Y154496D01*
G01X45453Y157861D02*
X48677Y154769D01*
G01X45691Y157861D02*
X48630Y155042D01*
G01X45928Y157861D02*
X48581Y155315D01*
G01X46164Y157861D02*
X48534Y155588D01*
G01X46402Y157861D02*
X48486Y155862D01*
G01X46639Y157861D02*
X48437Y156134D01*
G01X46875Y157861D02*
X48390Y156408D01*
G01X47112Y157861D02*
X48342Y156682D01*
G01X47350Y157861D02*
X48294Y156954D01*
G01X47586Y157861D02*
X48246Y157228D01*
G01X47823Y157861D02*
X48199Y157501D01*
G01X43725Y157702D02*
X43697Y157861D01*
X43796D01*
G01X43773Y157429D02*
X43725Y157702D01*
G01X43869Y156882D02*
X43820Y157156D01*
G01D02*
X43773Y157429D01*
G01X44271Y157861D02*
X44507D01*
G01D02*
X44743D01*
G01X43796D02*
X44033D01*
G01D02*
X44271D01*
G01X44743D02*
X44980D01*
G01X46402D02*
X46639D01*
G01X47586D02*
X47823D01*
G01X47112D02*
X47350D01*
G01X44980D02*
X45217D01*
G01X46875D02*
X47112D01*
G01X46639D02*
X46875D01*
G01X47350D02*
X47586D01*
G01X45691D02*
X45928D01*
G01X45453D02*
X45691D01*
G01X46164D02*
X46402D01*
G01X45217D02*
X45453D01*
G01X47823D02*
X48060D01*
G01X45928D02*
X46164D01*
G01X38346Y158091D02*
X42802Y153816D01*
G01X38562Y158111D02*
X43264Y153600D01*
G01X42342Y157665D02*
X49349Y150944D01*
G01X42813Y157442D02*
X49301Y151217D01*
G01X43462Y157045D02*
X49254Y151490D01*
G01X43869Y156882D02*
X49205Y151763D01*
G01X43820Y157156D02*
X49156Y152037D01*
G01X43773Y157429D02*
X49110Y152310D01*
G01X43725Y157702D02*
X49061Y152583D01*
G01X43796Y157861D02*
X49012Y152856D01*
G01X44033Y157861D02*
X48966Y153129D01*
G01X44271Y157861D02*
X48918Y153403D01*
G01X44507Y157861D02*
X48869Y153676D01*
G01X44743Y157861D02*
X48821Y153949D01*
G01X44980Y157861D02*
X48774Y154222D01*
G01X45217Y157861D02*
X48725Y154496D01*
G01X45453Y157861D02*
X48677Y154769D01*
G01X45691Y157861D02*
X48630Y155042D01*
G01X45928Y157861D02*
X48581Y155315D01*
G01X46164Y157861D02*
X48534Y155588D01*
G01X46402Y157861D02*
X48486Y155862D01*
G01X46639Y157861D02*
X48437Y156134D01*
G01X46875Y157861D02*
X48390Y156408D01*
G01X47112Y157861D02*
X48342Y156682D01*
G01X47350Y157861D02*
X48294Y156954D01*
G01X47586Y157861D02*
X48246Y157228D01*
G01X47823Y157861D02*
X48199Y157501D01*
G01X43725Y157702D02*
X43697Y157861D01*
X43796D01*
G01X43773Y157429D02*
X43725Y157702D01*
G01X43869Y156882D02*
X43820Y157156D01*
G01D02*
X43773Y157429D01*
G01X44271Y157861D02*
X44507D01*
G01D02*
X44743D01*
G01X43796D02*
X44033D01*
G01D02*
X44271D01*
G01X44743D02*
X44980D01*
G01X46402D02*
X46639D01*
G01X47586D02*
X47823D01*
G01X47112D02*
X47350D01*
G01X44980D02*
X45217D01*
G01X46875D02*
X47112D01*
G01X46639D02*
X46875D01*
G01X47350D02*
X47586D01*
G01X45691D02*
X45928D01*
G01X45453D02*
X45691D01*
G01X46164D02*
X46402D01*
G01X45217D02*
X45453D01*
G01X47823D02*
X48060D01*
G01X45928D02*
X46164D01*
G01X35267Y156044D02*
X39203Y152269D01*
G01X35351Y156193D02*
X39236Y152465D01*
G01X35455Y156321D02*
X39269Y152661D01*
G01X35558Y156449D02*
X39335Y152825D01*
G01X35661Y156577D02*
X39404Y152985D01*
G01X35764Y156706D02*
X39475Y153145D01*
G01X35867Y156834D02*
X39570Y153283D01*
G01X35970Y156962D02*
X39678Y153405D01*
G01X36089Y157074D02*
X39787Y153528D01*
G01X36229Y157168D02*
X39914Y153633D01*
G01X36369Y157261D02*
X40063Y153717D01*
G01X36507Y157356D02*
X40210Y153803D01*
G01X36645Y157449D02*
X40377Y153870D01*
G01X36784Y157544D02*
X40562Y153919D01*
G01X36923Y157638D02*
X40750Y153968D01*
G01X37085Y157710D02*
X40953Y153999D01*
G01X37260Y157769D02*
X41174Y154014D01*
G01X37437Y157827D02*
X41395Y154029D01*
G01X37614Y157885D02*
X41638Y154024D01*
G01X37790Y157943D02*
X41893Y154006D01*
G01X37966Y158001D02*
X42149Y153987D01*
G01X38143Y158059D02*
X42465Y153912D01*
G01X35267Y156044D02*
X39203Y152269D01*
G01X35351Y156193D02*
X39236Y152465D01*
G01X35455Y156321D02*
X39269Y152661D01*
G01X35558Y156449D02*
X39335Y152825D01*
G01X35661Y156577D02*
X39404Y152985D01*
G01X35764Y156706D02*
X39475Y153145D01*
G01X35867Y156834D02*
X39570Y153283D01*
G01X35970Y156962D02*
X39678Y153405D01*
G01X36089Y157074D02*
X39787Y153528D01*
G01X36229Y157168D02*
X39914Y153633D01*
G01X36369Y157261D02*
X40063Y153717D01*
G01X36507Y157356D02*
X40210Y153803D01*
G01X36645Y157449D02*
X40377Y153870D01*
G01X36784Y157544D02*
X40562Y153919D01*
G01X36923Y157638D02*
X40750Y153968D01*
G01X37085Y157710D02*
X40953Y153999D01*
G01X37260Y157769D02*
X41174Y154014D01*
G01X37437Y157827D02*
X41395Y154029D01*
G01X37614Y157885D02*
X41638Y154024D01*
G01X37790Y157943D02*
X41893Y154006D01*
G01X37966Y158001D02*
X42149Y153987D01*
G01X38143Y158059D02*
X42465Y153912D01*
G01X54055Y140976D02*
X53922Y141102D01*
G01X54293Y140976D02*
X53875Y141376D01*
G01X54529Y140976D02*
X53827Y141649D01*
G01X54765Y140976D02*
X53779Y141922D01*
G01X55003Y140976D02*
X53733Y142195D01*
G01X55240Y140976D02*
X53684Y142469D01*
G01X55477Y140976D02*
X53635Y142742D01*
G01X55713Y140976D02*
X53589Y143014D01*
G01X55950Y140976D02*
X53540Y143288D01*
G01X56187Y140976D02*
X53491Y143561D01*
G01X56423Y140976D02*
X53445Y143834D01*
G01X56660Y140976D02*
X53396Y144107D01*
G01X56898Y140976D02*
X53349Y144380D01*
G01X57135Y140976D02*
X53301Y144654D01*
G01X57372Y140976D02*
X53252Y144927D01*
G01X57608Y140976D02*
X53205Y145200D01*
G01X57845Y140976D02*
X53157Y145474D01*
G01X58082Y140976D02*
X53109Y145747D01*
G01X58318Y140976D02*
X53061Y146019D01*
G01X58352Y141171D02*
X53014Y146293D01*
G01X58303Y141445D02*
X52965Y146566D01*
G01X58255Y141719D02*
X52917Y146839D01*
G01X58206Y141992D02*
X52870Y147112D01*
G01X58753Y141695D02*
X52821Y147385D01*
G01X59350Y141350D02*
X52774Y147659D01*
G01X59824Y141122D02*
X52726Y147932D01*
G01X60205Y140984D02*
X52677Y148205D01*
G01X60542Y140888D02*
X52630Y148478D01*
G01X60879Y140793D02*
X52582Y148751D01*
G01X61186Y140725D02*
X52534Y149024D01*
G01X61449Y140701D02*
X52486Y149298D01*
G01X61713Y140673D02*
X52439Y149570D01*
G01X61976Y140649D02*
X52390Y149844D01*
G01X62240Y140622D02*
X52342Y150118D01*
G01X62467Y140631D02*
X52295Y150390D01*
G01X62695Y140641D02*
X52246Y150663D01*
G01X52198Y150937D02*
X62916Y140656D01*
G01X63127Y140682D02*
X58569Y145053D01*
G01X52151Y151210D02*
X57484Y146093D01*
G01X63337Y140706D02*
X59090Y144780D01*
G01X52102Y151483D02*
X57437Y146366D01*
G01X63537Y140741D02*
X59472Y144641D01*
G01X52055Y151756D02*
X57389Y146639D01*
G01X52007Y152029D02*
X57341Y146913D01*
G01X63732Y140782D02*
X59846Y144510D01*
G01X63927Y140821D02*
X60117Y144477D01*
G01X51960Y152303D02*
X57293Y147186D01*
G01X64110Y140874D02*
X60388Y144443D01*
G01X51939Y152549D02*
X57245Y147459D01*
G01X64290Y140928D02*
X60659Y144410D01*
G01X51919Y152795D02*
X57197Y147732D01*
G01X64471Y140983D02*
X60920Y144388D01*
G01X51899Y153042D02*
X57149Y148006D01*
G01X51880Y153288D02*
X57259Y148128D01*
G01X64639Y141048D02*
X61140Y144404D01*
G01X64805Y141116D02*
X61360Y144420D01*
G01X51859Y153534D02*
X57399Y148219D01*
G01X51866Y153755D02*
X57551Y148301D01*
G01X64971Y141183D02*
X61570Y144445D01*
G01X65126Y141262D02*
X61757Y144494D01*
G01X51893Y153956D02*
X57707Y148380D01*
G01X51920Y154157D02*
X57871Y148449D01*
G01X65278Y141343D02*
X61943Y144543D01*
G01X51948Y154358D02*
X58043Y148511D01*
G01X65430Y141425D02*
X62114Y144606D01*
G01X65573Y141515D02*
X62267Y144686D01*
G01X51976Y154558D02*
X58222Y148566D01*
G01X65711Y141609D02*
X62420Y144767D01*
G01X65849Y141704D02*
X62547Y144873D01*
G01X65980Y141806D02*
X62667Y144985D01*
G01X66104Y141914D02*
X62777Y145106D01*
G01X61722Y148390D02*
X57903Y152054D01*
G01X67115Y143217D02*
X62785Y147370D01*
G01X67192Y143370D02*
X58103Y152088D01*
G01X67259Y143533D02*
X58303Y152124D01*
G01X67318Y143703D02*
X58504Y152158D01*
G01X67378Y143873D02*
X58716Y152183D01*
G01X67429Y144051D02*
X58941Y152194D01*
G01X67470Y144239D02*
X59165Y152206D01*
G01X67510Y144428D02*
X59390Y152218D01*
G01X67545Y144622D02*
X59614Y152230D01*
G01X67563Y144831D02*
X59862Y152219D01*
G01X67582Y145041D02*
X60115Y152204D01*
G01X67596Y145255D02*
X60368Y152188D01*
G01X67590Y145487D02*
X60622Y152172D01*
G01X67585Y145720D02*
X60875Y152157D01*
G01X67573Y145958D02*
X61139Y152130D01*
G01X67541Y146217D02*
X61437Y152072D01*
G01X67507Y146476D02*
X61735Y152014D01*
G01X67455Y146753D02*
X62032Y151955D01*
G01X67368Y147064D02*
X62330Y151897D01*
G01X67281Y147374D02*
X62685Y151783D01*
G01X50643Y143567D02*
X50692Y143294D01*
G01X50597Y143840D02*
X50643Y143567D01*
G01X50548Y144113D02*
X50597Y143840D01*
G01X50548Y144113D02*
X50499Y144386D01*
G01X50692Y143294D02*
X50740Y143020D01*
G01D02*
X50788Y142747D01*
G01X50979Y141654D02*
X51028Y141381D01*
G01X50739Y140976D02*
X50503D01*
G01X51075Y141107D02*
X51099Y140976D01*
X50976D01*
G01X51028Y141381D02*
X51075Y141107D01*
G01X50788Y142747D02*
X50835Y142475D01*
G01D02*
X50884Y142201D01*
G01D02*
X50932Y141927D01*
G01D02*
X50979Y141654D01*
G01X50976Y140976D02*
X50739D01*
G01X48844D02*
X48608D01*
G01X48371D02*
X48134D01*
G01X49080D02*
X48844D01*
G01X48608D02*
X48371D01*
G01X49791D02*
X49555D01*
G01X50028D02*
X49791D01*
G01X50266D02*
X50028D01*
G01X49319D02*
X49080D01*
G01X49555D02*
X49319D01*
G01X50503D02*
X50266D01*
G01X50117Y146572D02*
X50164Y146299D01*
G01X50260Y145753D02*
X50308Y145480D01*
G01X50355Y145206D02*
X50404Y144933D01*
G01X50164Y146299D02*
X50211Y146026D01*
G01D02*
X50260Y145753D01*
G01X50308Y145480D02*
X50355Y145206D01*
G01X50404Y144933D02*
X50452Y144660D01*
G01D02*
X50499Y144386D01*
G01X50068Y146846D02*
X50117Y146572D01*
G01X49973Y147391D02*
X50020Y147119D01*
G01D02*
X50068Y146846D01*
G01X49876Y147939D02*
X49924Y147665D01*
G01X49780Y148485D02*
X49829Y148211D01*
G01D02*
X49876Y147939D01*
G01X49924Y147665D02*
X49973Y147391D01*
G01X49733Y148758D02*
X49780Y148485D01*
G01X57437Y146366D02*
X57484Y146093D01*
G01X57197Y147732D02*
X57245Y147459D01*
G01X57149Y148006D02*
X57197Y147732D01*
G01X52870Y147112D02*
X52821Y147385D01*
G01X57293Y147186D02*
X57341Y146913D01*
G01D02*
X57389Y146639D01*
G01X57245Y147459D02*
X57293Y147186D01*
G01X57389Y146639D02*
X57437Y146366D01*
G01X53061Y146019D02*
X53014Y146293D01*
G01X56187Y140976D02*
X55950D01*
G01X55713D02*
X55477D01*
G01D02*
X55240D01*
G01X55950D02*
X55713D01*
G01X54529D02*
X54293D01*
G01D02*
X54055D01*
G01X55003D02*
X54765D01*
G01D02*
X54529D01*
G01X56423D02*
X56187D01*
G01X55240D02*
X55003D01*
G01X56660D02*
X56423D01*
G01X57845D02*
X57608D01*
G01X58082D02*
X57845D01*
G01X58352Y141171D02*
X58386Y140976D01*
X58318D01*
G01D02*
X58082D01*
G01X58303Y141445D02*
X58352Y141171D01*
G01X56898Y140976D02*
X56660D01*
G01X57372D02*
X57135D01*
G01X57608D02*
X57372D01*
G01X57135D02*
X56898D01*
G01X58206Y141992D02*
X58255Y141719D01*
G01D02*
X58303Y141445D01*
G01X53252Y144927D02*
X53205Y145200D01*
G01X52965Y146566D02*
X52917Y146839D01*
G01D02*
X52870Y147112D01*
G01X53109Y145747D02*
X53061Y146019D01*
G01X53014Y146293D02*
X52965Y146566D01*
G01X52774Y147659D02*
X52726Y147932D01*
G01X52821Y147385D02*
X52774Y147659D01*
G01X53445Y143834D02*
X53396Y144107D01*
G01X53635Y142742D02*
X53589Y143014D01*
G01X53491Y143561D02*
X53445Y143834D01*
G01X53540Y143288D02*
X53491Y143561D01*
G01X53589Y143014D02*
X53540Y143288D01*
G01X53301Y144654D02*
X53252Y144927D01*
G01X53205Y145200D02*
X53157Y145474D01*
G01D02*
X53109Y145747D01*
G01X53349Y144380D02*
X53301Y144654D01*
G01X53396Y144107D02*
X53349Y144380D01*
G01X52677Y148205D02*
X52630Y148478D01*
G01D02*
X52582Y148751D01*
G01X52726Y147932D02*
X52677Y148205D01*
G01X53684Y142469D02*
X53635Y142742D01*
G01X54055Y140976D02*
X53945D01*
X53922Y141102D01*
G01D02*
X53875Y141376D01*
G01X53779Y141922D02*
X53733Y142195D01*
G01D02*
X53684Y142469D01*
G01X53875Y141376D02*
X53827Y141649D01*
G01D02*
X53779Y141922D01*
G01X54055Y140976D02*
X53922Y141102D01*
G01X54293Y140976D02*
X53875Y141376D01*
G01X54529Y140976D02*
X53827Y141649D01*
G01X54765Y140976D02*
X53779Y141922D01*
G01X55003Y140976D02*
X53733Y142195D01*
G01X55240Y140976D02*
X53684Y142469D01*
G01X55477Y140976D02*
X53635Y142742D01*
G01X55713Y140976D02*
X53589Y143014D01*
G01X55950Y140976D02*
X53540Y143288D01*
G01X56187Y140976D02*
X53491Y143561D01*
G01X56423Y140976D02*
X53445Y143834D01*
G01X56660Y140976D02*
X53396Y144107D01*
G01X56898Y140976D02*
X53349Y144380D01*
G01X57135Y140976D02*
X53301Y144654D01*
G01X57372Y140976D02*
X53252Y144927D01*
G01X57608Y140976D02*
X53205Y145200D01*
G01X57845Y140976D02*
X53157Y145474D01*
G01X58082Y140976D02*
X53109Y145747D01*
G01X58318Y140976D02*
X53061Y146019D01*
G01X58352Y141171D02*
X53014Y146293D01*
G01X58303Y141445D02*
X52965Y146566D01*
G01X58255Y141719D02*
X52917Y146839D01*
G01X58206Y141992D02*
X52870Y147112D01*
G01X58753Y141695D02*
X52821Y147385D01*
G01X59350Y141350D02*
X52774Y147659D01*
G01X59824Y141122D02*
X52726Y147932D01*
G01X60205Y140984D02*
X52677Y148205D01*
G01X60542Y140888D02*
X52630Y148478D01*
G01X60879Y140793D02*
X52582Y148751D01*
G01X61186Y140725D02*
X52534Y149024D01*
G01X61449Y140701D02*
X52486Y149298D01*
G01X61713Y140673D02*
X52439Y149570D01*
G01X61976Y140649D02*
X52390Y149844D01*
G01X62240Y140622D02*
X52342Y150118D01*
G01X62467Y140631D02*
X52295Y150390D01*
G01X62695Y140641D02*
X52246Y150663D01*
G01X52198Y150937D02*
X62916Y140656D01*
G01X63127Y140682D02*
X58569Y145053D01*
G01X52151Y151210D02*
X57484Y146093D01*
G01X63337Y140706D02*
X59090Y144780D01*
G01X52102Y151483D02*
X57437Y146366D01*
G01X63537Y140741D02*
X59472Y144641D01*
G01X52055Y151756D02*
X57389Y146639D01*
G01X52007Y152029D02*
X57341Y146913D01*
G01X63732Y140782D02*
X59846Y144510D01*
G01X63927Y140821D02*
X60117Y144477D01*
G01X51960Y152303D02*
X57293Y147186D01*
G01X64110Y140874D02*
X60388Y144443D01*
G01X51939Y152549D02*
X57245Y147459D01*
G01X64290Y140928D02*
X60659Y144410D01*
G01X51919Y152795D02*
X57197Y147732D01*
G01X64471Y140983D02*
X60920Y144388D01*
G01X51899Y153042D02*
X57149Y148006D01*
G01X51880Y153288D02*
X57259Y148128D01*
G01X64639Y141048D02*
X61140Y144404D01*
G01X64805Y141116D02*
X61360Y144420D01*
G01X51859Y153534D02*
X57399Y148219D01*
G01X51866Y153755D02*
X57551Y148301D01*
G01X64971Y141183D02*
X61570Y144445D01*
G01X65126Y141262D02*
X61757Y144494D01*
G01X51893Y153956D02*
X57707Y148380D01*
G01X51920Y154157D02*
X57871Y148449D01*
G01X65278Y141343D02*
X61943Y144543D01*
G01X51948Y154358D02*
X58043Y148511D01*
G01X65430Y141425D02*
X62114Y144606D01*
G01X65573Y141515D02*
X62267Y144686D01*
G01X51976Y154558D02*
X58222Y148566D01*
G01X65711Y141609D02*
X62420Y144767D01*
G01X65849Y141704D02*
X62547Y144873D01*
G01X65980Y141806D02*
X62667Y144985D01*
G01X66104Y141914D02*
X62777Y145106D01*
G01X61722Y148390D02*
X57903Y152054D01*
G01X67115Y143217D02*
X62785Y147370D01*
G01X67192Y143370D02*
X58103Y152088D01*
G01X67259Y143533D02*
X58303Y152124D01*
G01X67318Y143703D02*
X58504Y152158D01*
G01X67378Y143873D02*
X58716Y152183D01*
G01X67429Y144051D02*
X58941Y152194D01*
G01X67470Y144239D02*
X59165Y152206D01*
G01X67510Y144428D02*
X59390Y152218D01*
G01X67545Y144622D02*
X59614Y152230D01*
G01X67563Y144831D02*
X59862Y152219D01*
G01X67582Y145041D02*
X60115Y152204D01*
G01X67596Y145255D02*
X60368Y152188D01*
G01X67590Y145487D02*
X60622Y152172D01*
G01X67585Y145720D02*
X60875Y152157D01*
G01X67573Y145958D02*
X61139Y152130D01*
G01X67541Y146217D02*
X61437Y152072D01*
G01X67507Y146476D02*
X61735Y152014D01*
G01X67455Y146753D02*
X62032Y151955D01*
G01X67368Y147064D02*
X62330Y151897D01*
G01X67281Y147374D02*
X62685Y151783D01*
G01X50643Y143567D02*
X50692Y143294D01*
G01X50597Y143840D02*
X50643Y143567D01*
G01X50548Y144113D02*
X50597Y143840D01*
G01X50548Y144113D02*
X50499Y144386D01*
G01X50692Y143294D02*
X50740Y143020D01*
G01D02*
X50788Y142747D01*
G01X50979Y141654D02*
X51028Y141381D01*
G01X50739Y140976D02*
X50503D01*
G01X51075Y141107D02*
X51099Y140976D01*
X50976D01*
G01X51028Y141381D02*
X51075Y141107D01*
G01X50788Y142747D02*
X50835Y142475D01*
G01D02*
X50884Y142201D01*
G01D02*
X50932Y141927D01*
G01D02*
X50979Y141654D01*
G01X50976Y140976D02*
X50739D01*
G01X48844D02*
X48608D01*
G01X48371D02*
X48134D01*
G01X49080D02*
X48844D01*
G01X48608D02*
X48371D01*
G01X49791D02*
X49555D01*
G01X50028D02*
X49791D01*
G01X50266D02*
X50028D01*
G01X49319D02*
X49080D01*
G01X49555D02*
X49319D01*
G01X50503D02*
X50266D01*
G01X50117Y146572D02*
X50164Y146299D01*
G01X50260Y145753D02*
X50308Y145480D01*
G01X50355Y145206D02*
X50404Y144933D01*
G01X50164Y146299D02*
X50211Y146026D01*
G01D02*
X50260Y145753D01*
G01X50308Y145480D02*
X50355Y145206D01*
G01X50404Y144933D02*
X50452Y144660D01*
G01D02*
X50499Y144386D01*
G01X50068Y146846D02*
X50117Y146572D01*
G01X49973Y147391D02*
X50020Y147119D01*
G01D02*
X50068Y146846D01*
G01X49876Y147939D02*
X49924Y147665D01*
G01X49780Y148485D02*
X49829Y148211D01*
G01D02*
X49876Y147939D01*
G01X49924Y147665D02*
X49973Y147391D01*
G01X49733Y148758D02*
X49780Y148485D01*
G01X57437Y146366D02*
X57484Y146093D01*
G01X57197Y147732D02*
X57245Y147459D01*
G01X57149Y148006D02*
X57197Y147732D01*
G01X52870Y147112D02*
X52821Y147385D01*
G01X57293Y147186D02*
X57341Y146913D01*
G01D02*
X57389Y146639D01*
G01X57245Y147459D02*
X57293Y147186D01*
G01X57389Y146639D02*
X57437Y146366D01*
G01X53061Y146019D02*
X53014Y146293D01*
G01X56187Y140976D02*
X55950D01*
G01X55713D02*
X55477D01*
G01D02*
X55240D01*
G01X55950D02*
X55713D01*
G01X54529D02*
X54293D01*
G01D02*
X54055D01*
G01X55003D02*
X54765D01*
G01D02*
X54529D01*
G01X56423D02*
X56187D01*
G01X55240D02*
X55003D01*
G01X56660D02*
X56423D01*
G01X57845D02*
X57608D01*
G01X58082D02*
X57845D01*
G01X58352Y141171D02*
X58386Y140976D01*
X58318D01*
G01D02*
X58082D01*
G01X58303Y141445D02*
X58352Y141171D01*
G01X56898Y140976D02*
X56660D01*
G01X57372D02*
X57135D01*
G01X57608D02*
X57372D01*
G01X57135D02*
X56898D01*
G01X58206Y141992D02*
X58255Y141719D01*
G01D02*
X58303Y141445D01*
G01X53252Y144927D02*
X53205Y145200D01*
G01X52965Y146566D02*
X52917Y146839D01*
G01D02*
X52870Y147112D01*
G01X53109Y145747D02*
X53061Y146019D01*
G01X53014Y146293D02*
X52965Y146566D01*
G01X52774Y147659D02*
X52726Y147932D01*
G01X52821Y147385D02*
X52774Y147659D01*
G01X53445Y143834D02*
X53396Y144107D01*
G01X53635Y142742D02*
X53589Y143014D01*
G01X53491Y143561D02*
X53445Y143834D01*
G01X53540Y143288D02*
X53491Y143561D01*
G01X53589Y143014D02*
X53540Y143288D01*
G01X53301Y144654D02*
X53252Y144927D01*
G01X53205Y145200D02*
X53157Y145474D01*
G01D02*
X53109Y145747D01*
G01X53349Y144380D02*
X53301Y144654D01*
G01X53396Y144107D02*
X53349Y144380D01*
G01X52677Y148205D02*
X52630Y148478D01*
G01D02*
X52582Y148751D01*
G01X52726Y147932D02*
X52677Y148205D01*
G01X53684Y142469D02*
X53635Y142742D01*
G01X54055Y140976D02*
X53945D01*
X53922Y141102D01*
G01D02*
X53875Y141376D01*
G01X53779Y141922D02*
X53733Y142195D01*
G01D02*
X53684Y142469D01*
G01X53875Y141376D02*
X53827Y141649D01*
G01D02*
X53779Y141922D01*
G01X52003Y154759D02*
X58412Y148612D01*
G01X52059Y154935D02*
X58607Y148653D01*
G01X52124Y155097D02*
X58811Y148683D01*
G01X52192Y155260D02*
X59020Y148710D01*
G01X52260Y155423D02*
X59238Y148728D01*
G01X52326Y155586D02*
X59460Y148743D01*
G01X56685Y151631D02*
X59687Y148752D01*
G01X52392Y155749D02*
X56480Y151828D01*
G01X56844Y151706D02*
X59919Y148757D01*
G01X52475Y155897D02*
X56433Y152101D01*
G01X57003Y151780D02*
X60159Y148753D01*
G01X57174Y151845D02*
X60431Y148719D01*
G01X60704Y148685D02*
X57352Y151901D01*
G01X60976Y148651D02*
X57530Y151957D01*
G01X61257Y148609D02*
X57709Y152013D01*
G01X49205Y151763D02*
X49254Y151490D01*
G01D02*
X49301Y151217D01*
G01X49541Y149851D02*
X49589Y149577D01*
G01X49493Y150124D02*
X49541Y149851D01*
G01X49589Y149577D02*
X49636Y149304D01*
G01D02*
X49685Y149031D01*
G01D02*
X49733Y148758D01*
G01X49156Y152037D02*
X49205Y151763D01*
G01X49110Y152310D02*
X49156Y152037D01*
G01X49301Y151217D02*
X49349Y150944D01*
G01X49398Y150670D02*
X49445Y150397D01*
G01X49349Y150944D02*
X49398Y150670D01*
G01X49445Y150397D02*
X49493Y150124D01*
G01X52198Y150937D02*
X52246Y150663D01*
G01X52055Y151756D02*
X52102Y151483D01*
G01X52007Y152029D02*
X52055Y151756D01*
G01X52151Y151210D02*
X52198Y150937D01*
G01X52102Y151483D02*
X52151Y151210D01*
G01X52390Y149844D02*
X52342Y150118D01*
G01X52439Y149570D02*
X52390Y149844D01*
G01X52342Y150118D02*
X52295Y150390D01*
G01X52246Y150663D02*
X52295Y150390D01*
G01X52534Y149024D02*
X52486Y149298D01*
G01X52582Y148751D02*
X52534Y149024D01*
G01X52486Y149298D02*
X52439Y149570D01*
G01X56433Y152101D02*
X56480Y151828D01*
G01X56386Y152374D02*
X56433Y152101D01*
G01X52003Y154759D02*
X58412Y148612D01*
G01X52059Y154935D02*
X58607Y148653D01*
G01X52124Y155097D02*
X58811Y148683D01*
G01X52192Y155260D02*
X59020Y148710D01*
G01X52260Y155423D02*
X59238Y148728D01*
G01X52326Y155586D02*
X59460Y148743D01*
G01X56685Y151631D02*
X59687Y148752D01*
G01X52392Y155749D02*
X56480Y151828D01*
G01X56844Y151706D02*
X59919Y148757D01*
G01X52475Y155897D02*
X56433Y152101D01*
G01X57003Y151780D02*
X60159Y148753D01*
G01X57174Y151845D02*
X60431Y148719D01*
G01X60704Y148685D02*
X57352Y151901D01*
G01X60976Y148651D02*
X57530Y151957D01*
G01X61257Y148609D02*
X57709Y152013D01*
G01X49205Y151763D02*
X49254Y151490D01*
G01D02*
X49301Y151217D01*
G01X49541Y149851D02*
X49589Y149577D01*
G01X49493Y150124D02*
X49541Y149851D01*
G01X49589Y149577D02*
X49636Y149304D01*
G01D02*
X49685Y149031D01*
G01D02*
X49733Y148758D01*
G01X49156Y152037D02*
X49205Y151763D01*
G01X49110Y152310D02*
X49156Y152037D01*
G01X49301Y151217D02*
X49349Y150944D01*
G01X49398Y150670D02*
X49445Y150397D01*
G01X49349Y150944D02*
X49398Y150670D01*
G01X49445Y150397D02*
X49493Y150124D01*
G01X52198Y150937D02*
X52246Y150663D01*
G01X52055Y151756D02*
X52102Y151483D01*
G01X52007Y152029D02*
X52055Y151756D01*
G01X52151Y151210D02*
X52198Y150937D01*
G01X52102Y151483D02*
X52151Y151210D01*
G01X52390Y149844D02*
X52342Y150118D01*
G01X52439Y149570D02*
X52390Y149844D01*
G01X52342Y150118D02*
X52295Y150390D01*
G01X52246Y150663D02*
X52295Y150390D01*
G01X52534Y149024D02*
X52486Y149298D01*
G01X52582Y148751D02*
X52534Y149024D01*
G01X52486Y149298D02*
X52439Y149570D01*
G01X56433Y152101D02*
X56480Y151828D01*
G01X56386Y152374D02*
X56433Y152101D01*
G01X48060Y157861D02*
X48150Y157774D01*
G01X52577Y156027D02*
X56386Y152374D01*
G01X52677Y156157D02*
X56360Y152625D01*
G01X52779Y156287D02*
X56346Y152866D01*
G01X52881Y156417D02*
X56367Y153072D01*
G01X52981Y156547D02*
X56397Y153271D01*
G01X53084Y156678D02*
X56455Y153443D01*
G01X53216Y156777D02*
X56516Y153611D01*
G01X53347Y156878D02*
X56607Y153751D01*
G01X53480Y156978D02*
X56699Y153890D01*
G01X53613Y157078D02*
X56815Y154006D01*
G01X53746Y157178D02*
X56938Y154115D01*
G01X53878Y157278D02*
X57073Y154213D01*
G01X54020Y157368D02*
X57226Y154293D01*
G01X54183Y157440D02*
X57380Y154373D01*
G01X54346Y157512D02*
X57563Y154425D01*
G01X54507Y157584D02*
X57748Y154474D01*
G01X54669Y157655D02*
X57947Y154511D01*
G01X54831Y157727D02*
X58166Y154528D01*
G01X54993Y157799D02*
X58385Y154545D01*
G01X55174Y157852D02*
X58623Y154543D01*
G01X55366Y157896D02*
X58866Y154539D01*
G01X55557Y157940D02*
X59108Y154534D01*
G01X55748Y157984D02*
X59361Y154518D01*
G01X55939Y158028D02*
X59615Y154501D01*
G01X56131Y158071D02*
X59877Y154478D01*
G01X56322Y158115D02*
X60150Y154442D01*
G01X56543Y158130D02*
X60427Y154404D01*
G01X56763Y158145D02*
X60726Y154344D01*
G01X56985Y158160D02*
X61034Y154276D01*
G01X57206Y158176D02*
X61367Y154184D01*
G01X57427Y158191D02*
X61723Y154069D01*
G01X57648Y158205D02*
X62102Y153932D01*
G01X57880Y158211D02*
X62524Y153755D01*
G01X58124Y158204D02*
X62980Y153545D01*
G01X58368Y158197D02*
X63270Y153494D01*
G01X58611Y158191D02*
X63333Y153661D01*
G01X58863Y158177D02*
X63396Y153828D01*
G01X59124Y158153D02*
X63459Y153995D01*
G01X59385Y158130D02*
X63521Y154162D01*
G01X59645Y158107D02*
X63584Y154329D01*
G01X59929Y158063D02*
X63647Y154496D01*
G01X60213Y158018D02*
X63710Y154663D01*
G01X60497Y157972D02*
X63773Y154830D01*
G01X60809Y157900D02*
X63836Y154996D01*
G01X61123Y157827D02*
X63898Y155163D01*
G01X61451Y157739D02*
X63961Y155331D01*
G01X61801Y157630D02*
X64024Y155498D01*
G01X62160Y157512D02*
X64087Y155664D01*
G01X62555Y157361D02*
X64150Y155831D01*
G01X48725Y154496D02*
X48677Y154769D01*
G01D02*
X48630Y155042D01*
G01X48581Y155315D02*
X48534Y155588D01*
G01X48821Y153949D02*
X48869Y153676D01*
G01D02*
X48918Y153403D01*
G01X48774Y154222D02*
X48725Y154496D01*
G01X48821Y153949D02*
X48774Y154222D01*
G01X48534Y155588D02*
X48486Y155862D01*
G01X48630Y155042D02*
X48581Y155315D01*
G01X48060Y157861D02*
X48135D01*
X48150Y157774D01*
G01X48199Y157501D02*
X48150Y157774D01*
G01X48437Y156134D02*
X48390Y156408D01*
G01X48486Y155862D02*
X48437Y156134D01*
G01X48246Y157228D02*
X48199Y157501D01*
G01X48390Y156408D02*
X48342Y156682D01*
G01D02*
X48294Y156954D01*
G01D02*
X48246Y157228D01*
G01X48918Y153403D02*
X48966Y153129D01*
G01D02*
X49012Y152856D01*
G01X49061Y152583D02*
X49110Y152310D01*
G01X49012Y152856D02*
X49061Y152583D01*
G01X48060Y157861D02*
X48150Y157774D01*
G01X52577Y156027D02*
X56386Y152374D01*
G01X52677Y156157D02*
X56360Y152625D01*
G01X52779Y156287D02*
X56346Y152866D01*
G01X52881Y156417D02*
X56367Y153072D01*
G01X52981Y156547D02*
X56397Y153271D01*
G01X53084Y156678D02*
X56455Y153443D01*
G01X53216Y156777D02*
X56516Y153611D01*
G01X53347Y156878D02*
X56607Y153751D01*
G01X53480Y156978D02*
X56699Y153890D01*
G01X53613Y157078D02*
X56815Y154006D01*
G01X53746Y157178D02*
X56938Y154115D01*
G01X53878Y157278D02*
X57073Y154213D01*
G01X54020Y157368D02*
X57226Y154293D01*
G01X54183Y157440D02*
X57380Y154373D01*
G01X54346Y157512D02*
X57563Y154425D01*
G01X54507Y157584D02*
X57748Y154474D01*
G01X54669Y157655D02*
X57947Y154511D01*
G01X54831Y157727D02*
X58166Y154528D01*
G01X54993Y157799D02*
X58385Y154545D01*
G01X55174Y157852D02*
X58623Y154543D01*
G01X55366Y157896D02*
X58866Y154539D01*
G01X55557Y157940D02*
X59108Y154534D01*
G01X55748Y157984D02*
X59361Y154518D01*
G01X55939Y158028D02*
X59615Y154501D01*
G01X56131Y158071D02*
X59877Y154478D01*
G01X56322Y158115D02*
X60150Y154442D01*
G01X56543Y158130D02*
X60427Y154404D01*
G01X56763Y158145D02*
X60726Y154344D01*
G01X56985Y158160D02*
X61034Y154276D01*
G01X57206Y158176D02*
X61367Y154184D01*
G01X57427Y158191D02*
X61723Y154069D01*
G01X57648Y158205D02*
X62102Y153932D01*
G01X57880Y158211D02*
X62524Y153755D01*
G01X58124Y158204D02*
X62980Y153545D01*
G01X58368Y158197D02*
X63270Y153494D01*
G01X58611Y158191D02*
X63333Y153661D01*
G01X58863Y158177D02*
X63396Y153828D01*
G01X59124Y158153D02*
X63459Y153995D01*
G01X59385Y158130D02*
X63521Y154162D01*
G01X59645Y158107D02*
X63584Y154329D01*
G01X59929Y158063D02*
X63647Y154496D01*
G01X60213Y158018D02*
X63710Y154663D01*
G01X60497Y157972D02*
X63773Y154830D01*
G01X60809Y157900D02*
X63836Y154996D01*
G01X61123Y157827D02*
X63898Y155163D01*
G01X61451Y157739D02*
X63961Y155331D01*
G01X61801Y157630D02*
X64024Y155498D01*
G01X62160Y157512D02*
X64087Y155664D01*
G01X62555Y157361D02*
X64150Y155831D01*
G01X48725Y154496D02*
X48677Y154769D01*
G01D02*
X48630Y155042D01*
G01X48581Y155315D02*
X48534Y155588D01*
G01X48821Y153949D02*
X48869Y153676D01*
G01D02*
X48918Y153403D01*
G01X48774Y154222D02*
X48725Y154496D01*
G01X48821Y153949D02*
X48774Y154222D01*
G01X48534Y155588D02*
X48486Y155862D01*
G01X48630Y155042D02*
X48581Y155315D01*
G01X48060Y157861D02*
X48135D01*
X48150Y157774D01*
G01X48199Y157501D02*
X48150Y157774D01*
G01X48437Y156134D02*
X48390Y156408D01*
G01X48486Y155862D02*
X48437Y156134D01*
G01X48246Y157228D02*
X48199Y157501D01*
G01X48390Y156408D02*
X48342Y156682D01*
G01D02*
X48294Y156954D01*
G01D02*
X48246Y157228D01*
G01X48918Y153403D02*
X48966Y153129D01*
G01D02*
X49012Y152856D01*
G01X49061Y152583D02*
X49110Y152310D01*
G01X49012Y152856D02*
X49061Y152583D01*
G01X66228Y142022D02*
X62863Y145250D01*
G01X66348Y142135D02*
X62950Y145395D01*
G01X66458Y142257D02*
X63003Y145570D01*
G01X66567Y142379D02*
X63055Y145748D01*
G01X66675Y142502D02*
X63077Y145954D01*
G01X66769Y142640D02*
X63092Y146167D01*
G01X66863Y142777D02*
X63072Y146413D01*
G01X66957Y142914D02*
X63036Y146675D01*
G01X67037Y143064D02*
X62911Y147022D01*
G01X70872Y140976D02*
X70753Y141090D01*
G01X71109Y140976D02*
X70704Y141364D01*
G01X71346Y140976D02*
X70657Y141637D01*
G01X71583Y140976D02*
X70609Y141910D01*
G01X71819Y140976D02*
X70561Y142183D01*
G01X72057Y140976D02*
X70512Y142457D01*
G01X72293Y140976D02*
X70464Y142730D01*
G01X72530Y140976D02*
X70417Y143003D01*
G01X72767Y140976D02*
X70369Y143276D01*
G01X73003Y140976D02*
X70321Y143550D01*
G01X73241Y140976D02*
X70272Y143824D01*
G01X73477Y140976D02*
X70224Y144096D01*
G01X73714Y140976D02*
X70177Y144369D01*
G01X73951Y140976D02*
X70129Y144643D01*
G01X67193Y147686D02*
X63060Y151651D01*
G01X74188Y140976D02*
X70080Y144916D01*
G01X67084Y148018D02*
X63434Y151519D01*
G01X74425Y140976D02*
X70032Y145189D01*
G01X74661Y140976D02*
X69984Y145463D01*
G01X66846Y148473D02*
X63885Y151313D01*
G01X74898Y140976D02*
X69937Y145736D01*
G01X75136Y140976D02*
X69889Y146009D01*
G01X75178Y141162D02*
X69840Y146283D01*
G01X75130Y141436D02*
X69792Y146556D01*
G01X75083Y141708D02*
X69744Y146829D01*
G01X75034Y141982D02*
X69697Y147102D01*
G01X75538Y141725D02*
X69648Y147376D01*
G01X76143Y141372D02*
X69600Y147648D01*
G01X76613Y141149D02*
X69552Y147922D01*
G01X77000Y141004D02*
X69504Y148196D01*
G01X77333Y140912D02*
X69457Y148469D01*
G01X77667Y140820D02*
X69408Y148742D01*
G01X77990Y140737D02*
X69360Y149016D01*
G01X78252Y140713D02*
X69312Y149289D01*
G01X78514Y140688D02*
X69264Y149562D01*
G01X78776Y140665D02*
X69216Y149835D01*
G01X79038Y140641D02*
X69168Y150108D01*
G01X79288Y140627D02*
X69120Y150382D01*
G01X79504Y140648D02*
X69072Y150655D01*
G01X79720Y140668D02*
X69024Y150928D01*
G01X79936Y140687D02*
X68976Y151201D01*
G01X68928Y151475D02*
X80152Y140709D01*
G01X74754Y146113D02*
X68880Y151748D01*
G01X80368Y140728D02*
X75686Y145220D01*
G01X74493Y146590D02*
X68832Y152021D01*
G01X80584Y140747D02*
X76147Y145004D01*
G01X80783Y140783D02*
X76471Y144921D01*
G01X74315Y146989D02*
X68784Y152295D01*
G01X80960Y140842D02*
X76783Y144848D01*
G01X74194Y147332D02*
X68736Y152569D01*
G01X68688Y152841D02*
X74082Y147667D01*
G01X81136Y140900D02*
X77038Y144831D01*
G01X81312Y140958D02*
X77292Y144814D01*
G01X68640Y153114D02*
X74017Y147956D01*
G01X81489Y141015D02*
X77531Y144812D01*
G01X68592Y153388D02*
X73951Y148247D01*
G01X68544Y153661D02*
X73886Y148537D01*
G01X69697Y147102D02*
X69648Y147376D01*
G01X71109Y140976D02*
X70872D01*
G01X72057D02*
X71819D01*
G01D02*
X71583D01*
G01X72530D02*
X72293D01*
G01D02*
X72057D01*
G01X71346D02*
X71109D01*
G01X71583D02*
X71346D01*
G01X72767D02*
X72530D01*
G01X74898D02*
X74661D01*
G01X73003D02*
X72767D01*
G01X74425D02*
X74188D01*
G01D02*
X73951D01*
G01X74661D02*
X74425D01*
G01X73241D02*
X73003D01*
G01X75136D02*
X74898D01*
G01X73477D02*
X73241D01*
G01X73714D02*
X73477D01*
G01X73951D02*
X73714D01*
G01X75034Y141982D02*
X75083Y141708D01*
G01X75130Y141436D02*
X75178Y141162D01*
G01X75083Y141708D02*
X75130Y141436D01*
G01X75178Y141162D02*
X75210Y140976D01*
X75136D01*
G01X70609Y141910D02*
X70657Y141637D01*
G01D02*
X70704Y141364D01*
G01X70561Y142183D02*
X70609Y141910D01*
G01X70704Y141364D02*
X70753Y141090D01*
G01X70872Y140976D02*
X70773D01*
X70753Y141090D01*
G01X70369Y143276D02*
X70417Y143003D01*
G01D02*
X70464Y142730D01*
G01D02*
X70512Y142457D01*
G01D02*
X70561Y142183D01*
G01X70321Y143550D02*
X70369Y143276D01*
G01X69600Y147648D02*
X69552Y147922D01*
G01X69792Y146556D02*
X69744Y146829D01*
G01D02*
X69697Y147102D01*
G01X69648Y147376D02*
X69600Y147648D01*
G01X69552Y147922D02*
X69504Y148196D01*
G01D02*
X69457Y148469D01*
G01D02*
X69408Y148742D01*
G01X70177Y144369D02*
X70224Y144096D01*
G01X70080Y144916D02*
X70129Y144643D01*
G01D02*
X70177Y144369D01*
G01X70272Y143824D02*
X70321Y143550D01*
G01X70224Y144096D02*
X70272Y143824D01*
G01X70032Y145189D02*
X70080Y144916D01*
G01X69889Y146009D02*
X69937Y145736D01*
G01X69889Y146009D02*
X69840Y146283D01*
G01X69984Y145463D02*
X70032Y145189D01*
G01X69937Y145736D02*
X69984Y145463D01*
G01X69840Y146283D02*
X69792Y146556D01*
G01X66228Y142022D02*
X62863Y145250D01*
G01X66348Y142135D02*
X62950Y145395D01*
G01X66458Y142257D02*
X63003Y145570D01*
G01X66567Y142379D02*
X63055Y145748D01*
G01X66675Y142502D02*
X63077Y145954D01*
G01X66769Y142640D02*
X63092Y146167D01*
G01X66863Y142777D02*
X63072Y146413D01*
G01X66957Y142914D02*
X63036Y146675D01*
G01X67037Y143064D02*
X62911Y147022D01*
G01X70872Y140976D02*
X70753Y141090D01*
G01X71109Y140976D02*
X70704Y141364D01*
G01X71346Y140976D02*
X70657Y141637D01*
G01X71583Y140976D02*
X70609Y141910D01*
G01X71819Y140976D02*
X70561Y142183D01*
G01X72057Y140976D02*
X70512Y142457D01*
G01X72293Y140976D02*
X70464Y142730D01*
G01X72530Y140976D02*
X70417Y143003D01*
G01X72767Y140976D02*
X70369Y143276D01*
G01X73003Y140976D02*
X70321Y143550D01*
G01X73241Y140976D02*
X70272Y143824D01*
G01X73477Y140976D02*
X70224Y144096D01*
G01X73714Y140976D02*
X70177Y144369D01*
G01X73951Y140976D02*
X70129Y144643D01*
G01X67193Y147686D02*
X63060Y151651D01*
G01X74188Y140976D02*
X70080Y144916D01*
G01X67084Y148018D02*
X63434Y151519D01*
G01X74425Y140976D02*
X70032Y145189D01*
G01X74661Y140976D02*
X69984Y145463D01*
G01X66846Y148473D02*
X63885Y151313D01*
G01X74898Y140976D02*
X69937Y145736D01*
G01X75136Y140976D02*
X69889Y146009D01*
G01X75178Y141162D02*
X69840Y146283D01*
G01X75130Y141436D02*
X69792Y146556D01*
G01X75083Y141708D02*
X69744Y146829D01*
G01X75034Y141982D02*
X69697Y147102D01*
G01X75538Y141725D02*
X69648Y147376D01*
G01X76143Y141372D02*
X69600Y147648D01*
G01X76613Y141149D02*
X69552Y147922D01*
G01X77000Y141004D02*
X69504Y148196D01*
G01X77333Y140912D02*
X69457Y148469D01*
G01X77667Y140820D02*
X69408Y148742D01*
G01X77990Y140737D02*
X69360Y149016D01*
G01X78252Y140713D02*
X69312Y149289D01*
G01X78514Y140688D02*
X69264Y149562D01*
G01X78776Y140665D02*
X69216Y149835D01*
G01X79038Y140641D02*
X69168Y150108D01*
G01X79288Y140627D02*
X69120Y150382D01*
G01X79504Y140648D02*
X69072Y150655D01*
G01X79720Y140668D02*
X69024Y150928D01*
G01X79936Y140687D02*
X68976Y151201D01*
G01X68928Y151475D02*
X80152Y140709D01*
G01X74754Y146113D02*
X68880Y151748D01*
G01X80368Y140728D02*
X75686Y145220D01*
G01X74493Y146590D02*
X68832Y152021D01*
G01X80584Y140747D02*
X76147Y145004D01*
G01X80783Y140783D02*
X76471Y144921D01*
G01X74315Y146989D02*
X68784Y152295D01*
G01X80960Y140842D02*
X76783Y144848D01*
G01X74194Y147332D02*
X68736Y152569D01*
G01X68688Y152841D02*
X74082Y147667D01*
G01X81136Y140900D02*
X77038Y144831D01*
G01X81312Y140958D02*
X77292Y144814D01*
G01X68640Y153114D02*
X74017Y147956D01*
G01X81489Y141015D02*
X77531Y144812D01*
G01X68592Y153388D02*
X73951Y148247D01*
G01X68544Y153661D02*
X73886Y148537D01*
G01X69697Y147102D02*
X69648Y147376D01*
G01X71109Y140976D02*
X70872D01*
G01X72057D02*
X71819D01*
G01D02*
X71583D01*
G01X72530D02*
X72293D01*
G01D02*
X72057D01*
G01X71346D02*
X71109D01*
G01X71583D02*
X71346D01*
G01X72767D02*
X72530D01*
G01X74898D02*
X74661D01*
G01X73003D02*
X72767D01*
G01X74425D02*
X74188D01*
G01D02*
X73951D01*
G01X74661D02*
X74425D01*
G01X73241D02*
X73003D01*
G01X75136D02*
X74898D01*
G01X73477D02*
X73241D01*
G01X73714D02*
X73477D01*
G01X73951D02*
X73714D01*
G01X75034Y141982D02*
X75083Y141708D01*
G01X75130Y141436D02*
X75178Y141162D01*
G01X75083Y141708D02*
X75130Y141436D01*
G01X75178Y141162D02*
X75210Y140976D01*
X75136D01*
G01X70609Y141910D02*
X70657Y141637D01*
G01D02*
X70704Y141364D01*
G01X70561Y142183D02*
X70609Y141910D01*
G01X70704Y141364D02*
X70753Y141090D01*
G01X70872Y140976D02*
X70773D01*
X70753Y141090D01*
G01X70369Y143276D02*
X70417Y143003D01*
G01D02*
X70464Y142730D01*
G01D02*
X70512Y142457D01*
G01D02*
X70561Y142183D01*
G01X70321Y143550D02*
X70369Y143276D01*
G01X69600Y147648D02*
X69552Y147922D01*
G01X69792Y146556D02*
X69744Y146829D01*
G01D02*
X69697Y147102D01*
G01X69648Y147376D02*
X69600Y147648D01*
G01X69552Y147922D02*
X69504Y148196D01*
G01D02*
X69457Y148469D01*
G01D02*
X69408Y148742D01*
G01X70177Y144369D02*
X70224Y144096D01*
G01X70080Y144916D02*
X70129Y144643D01*
G01D02*
X70177Y144369D01*
G01X70272Y143824D02*
X70321Y143550D01*
G01X70224Y144096D02*
X70272Y143824D01*
G01X70032Y145189D02*
X70080Y144916D01*
G01X69889Y146009D02*
X69937Y145736D01*
G01X69889Y146009D02*
X69840Y146283D01*
G01X69984Y145463D02*
X70032Y145189D01*
G01X69937Y145736D02*
X69984Y145463D01*
G01X69840Y146283D02*
X69792Y146556D01*
G01X66608Y148929D02*
X64437Y151011D01*
G01X68496Y153934D02*
X73833Y148815D01*
G01X68448Y154207D02*
X73785Y149088D01*
G01X68400Y154481D02*
X73737Y149361D01*
G01X68352Y154754D02*
X73689Y149635D01*
G01X68304Y155028D02*
X73641Y149907D01*
G01X68256Y155300D02*
X73593Y150180D01*
G01X68208Y155574D02*
X73545Y150454D01*
G01X68160Y155847D02*
X73497Y150727D01*
G01X68112Y156121D02*
X73450Y151000D01*
G01X68064Y156393D02*
X73402Y151273D01*
G01X68015Y156667D02*
X73354Y151546D01*
G01X67967Y156941D02*
X73306Y151820D01*
G01X67920Y157214D02*
X73258Y152092D01*
G01X68832Y152021D02*
X68784Y152295D01*
G01X68880Y151748D02*
X68832Y152021D01*
G01X69312Y149289D02*
X69264Y149562D01*
G01X69216Y149835D02*
X69168Y150108D01*
G01X69264Y149562D02*
X69216Y149835D01*
G01X68928Y151475D02*
X68976Y151201D01*
G01X69120Y150382D02*
X69072Y150655D01*
G01X68976Y151201D02*
X69024Y150928D01*
G01X69072Y150655D02*
X69024Y150928D01*
G01X69168Y150108D02*
X69120Y150382D01*
G01X68928Y151475D02*
X68880Y151748D01*
G01X69360Y149016D02*
X69312Y149289D01*
G01X73737Y149361D02*
X73785Y149088D01*
G01D02*
X73833Y148815D01*
G01X73689Y149635D02*
X73737Y149361D01*
G01X69408Y148742D02*
X69360Y149016D01*
G01X73258Y152092D02*
X73306Y151820D01*
G01X73641Y149907D02*
X73689Y149635D01*
G01X73306Y151820D02*
X73354Y151546D01*
G01D02*
X73402Y151273D01*
G01X73210Y152365D02*
X73258Y152092D01*
G01X73545Y150454D02*
X73593Y150180D01*
G01D02*
X73641Y149907D01*
G01X73402Y151273D02*
X73450Y151000D01*
G01X73497Y150727D02*
X73545Y150454D01*
G01X73450Y151000D02*
X73497Y150727D01*
G01X66608Y148929D02*
X64437Y151011D01*
G01X68496Y153934D02*
X73833Y148815D01*
G01X68448Y154207D02*
X73785Y149088D01*
G01X68400Y154481D02*
X73737Y149361D01*
G01X68352Y154754D02*
X73689Y149635D01*
G01X68304Y155028D02*
X73641Y149907D01*
G01X68256Y155300D02*
X73593Y150180D01*
G01X68208Y155574D02*
X73545Y150454D01*
G01X68160Y155847D02*
X73497Y150727D01*
G01X68112Y156121D02*
X73450Y151000D01*
G01X68064Y156393D02*
X73402Y151273D01*
G01X68015Y156667D02*
X73354Y151546D01*
G01X67967Y156941D02*
X73306Y151820D01*
G01X67920Y157214D02*
X73258Y152092D01*
G01X68832Y152021D02*
X68784Y152295D01*
G01X68880Y151748D02*
X68832Y152021D01*
G01X69312Y149289D02*
X69264Y149562D01*
G01X69216Y149835D02*
X69168Y150108D01*
G01X69264Y149562D02*
X69216Y149835D01*
G01X68928Y151475D02*
X68976Y151201D01*
G01X69120Y150382D02*
X69072Y150655D01*
G01X68976Y151201D02*
X69024Y150928D01*
G01X69072Y150655D02*
X69024Y150928D01*
G01X69168Y150108D02*
X69120Y150382D01*
G01X68928Y151475D02*
X68880Y151748D01*
G01X69360Y149016D02*
X69312Y149289D01*
G01X73737Y149361D02*
X73785Y149088D01*
G01D02*
X73833Y148815D01*
G01X73689Y149635D02*
X73737Y149361D01*
G01X69408Y148742D02*
X69360Y149016D01*
G01X73258Y152092D02*
X73306Y151820D01*
G01X73641Y149907D02*
X73689Y149635D01*
G01X73306Y151820D02*
X73354Y151546D01*
G01D02*
X73402Y151273D01*
G01X73210Y152365D02*
X73258Y152092D01*
G01X73545Y150454D02*
X73593Y150180D01*
G01D02*
X73641Y149907D01*
G01X73402Y151273D02*
X73450Y151000D01*
G01X73497Y150727D02*
X73545Y150454D01*
G01X73450Y151000D02*
X73497Y150727D01*
G01X62964Y157196D02*
X64213Y155999D01*
G01X63408Y156998D02*
X64275Y156165D01*
G01X63879Y156772D02*
X64338Y156332D01*
G01X64376Y156523D02*
X64401Y156499D01*
G01X67872Y157487D02*
X73210Y152365D01*
G01X67824Y157760D02*
X73162Y152639D01*
G01X67956Y157861D02*
X73115Y152912D01*
G01X68192Y157861D02*
X73066Y153185D01*
G01X68429Y157861D02*
X73019Y153458D01*
G01X68666Y157861D02*
X72971Y153731D01*
G01X68903Y157861D02*
X72923Y154005D01*
G01X69140Y157861D02*
X72875Y154278D01*
G01X69377Y157861D02*
X72827Y154550D01*
G01X69613Y157861D02*
X72780Y154824D01*
G01X69851Y157861D02*
X72731Y155097D01*
G01X70087Y157861D02*
X72684Y155370D01*
G01X70324Y157861D02*
X72636Y155643D01*
G01X70561Y157861D02*
X72588Y155916D01*
G01X70798Y157861D02*
X72540Y156190D01*
G01X71035Y157861D02*
X72492Y156463D01*
G01X71271Y157861D02*
X72445Y156735D01*
G01X71508Y157861D02*
X72396Y157009D01*
G01X71745Y157861D02*
X72348Y157282D01*
G01X71982Y157861D02*
X72301Y157555D01*
G01X72219Y157861D02*
X72253Y157828D01*
G01X64213Y155999D02*
X64275Y156165D01*
G01X64213Y155999D02*
X64150Y155831D01*
G01X64275Y156165D02*
X64338Y156332D01*
G01D02*
X64401Y156499D01*
G01X64150Y155831D02*
X64087Y155664D01*
G01X63961Y155331D02*
X63898Y155163D01*
G01X64024Y155498D02*
X63961Y155331D01*
G01X64087Y155664D02*
X64024Y155498D01*
G01X63898Y155163D02*
X63836Y154996D01*
G01X63333Y153661D02*
X63270Y153494D01*
G01X63647Y154496D02*
X63584Y154329D01*
G01X63710Y154663D02*
X63647Y154496D01*
G01X63773Y154830D02*
X63710Y154663D01*
G01X63584Y154329D02*
X63521Y154162D01*
G01X63396Y153828D02*
X63333Y153661D01*
G01X63836Y154996D02*
X63773Y154830D01*
G01X63521Y154162D02*
X63459Y153995D01*
G01D02*
X63396Y153828D01*
G01X73066Y153185D02*
X73115Y152912D01*
G01X69377Y157861D02*
X69613D01*
G01X69140D02*
X69377D01*
G01X69851D02*
X70087D01*
G01D02*
X70324D01*
G01X68192D02*
X68429D01*
G01X68903D02*
X69140D01*
G01X68429D02*
X68666D01*
G01D02*
X68903D01*
G01X71271D02*
X71508D01*
G01D02*
X71745D01*
G01D02*
X71982D01*
G01D02*
X72219D01*
G01X70561D02*
X70798D01*
G01X71035D02*
X71271D01*
G01X67956D02*
X68192D01*
G01X70798D02*
X71035D01*
G01X70324D02*
X70561D01*
G01X68496Y153934D02*
X68448Y154207D01*
G01X68544Y153661D02*
X68496Y153934D01*
G01X68352Y154754D02*
X68304Y155028D01*
G01X67824Y157760D02*
X67806Y157861D01*
X67956D01*
G01X68400Y154481D02*
X68352Y154754D01*
G01X68736Y152569D02*
X68688Y152841D01*
G01X68640Y153114D02*
X68592Y153388D01*
G01D02*
X68544Y153661D01*
G01X68688Y152841D02*
X68640Y153114D01*
G01X68448Y154207D02*
X68400Y154481D01*
G01X68015Y156667D02*
X67967Y156941D01*
G01D02*
X67920Y157214D01*
G01X68304Y155028D02*
X68256Y155300D01*
G01X67920Y157214D02*
X67872Y157487D01*
G01D02*
X67824Y157760D01*
G01X68208Y155574D02*
X68160Y155847D01*
G01X68256Y155300D02*
X68208Y155574D01*
G01X68064Y156393D02*
X68015Y156667D01*
G01X68112Y156121D02*
X68064Y156393D01*
G01X68160Y155847D02*
X68112Y156121D01*
G01X69613Y157861D02*
X69851D01*
G01X68736Y152569D02*
X68784Y152295D01*
G01X72301Y157555D02*
X72253Y157828D01*
G01X72396Y157009D02*
X72348Y157282D01*
G01X72219Y157861D02*
X72247D01*
X72253Y157828D01*
G01X72588Y155916D02*
X72540Y156190D01*
G01X72492Y156463D02*
X72445Y156735D01*
G01D02*
X72396Y157009D01*
G01X72540Y156190D02*
X72492Y156463D01*
G01X72636Y155643D02*
X72588Y155916D01*
G01X72348Y157282D02*
X72301Y157555D01*
G01X73162Y152639D02*
X73210Y152365D01*
G01X72684Y155370D02*
X72636Y155643D01*
G01X72827Y154550D02*
X72875Y154278D01*
G01X72780Y154824D02*
X72827Y154550D01*
G01X72731Y155097D02*
X72684Y155370D01*
G01X72731Y155097D02*
X72780Y154824D01*
G01X72923Y154005D02*
X72971Y153731D01*
G01X73115Y152912D02*
X73162Y152639D01*
G01X73019Y153458D02*
X73066Y153185D01*
G01X72971Y153731D02*
X73019Y153458D01*
G01X72875Y154278D02*
X72923Y154005D01*
G01X62964Y157196D02*
X64213Y155999D01*
G01X63408Y156998D02*
X64275Y156165D01*
G01X63879Y156772D02*
X64338Y156332D01*
G01X64376Y156523D02*
X64401Y156499D01*
G01X67872Y157487D02*
X73210Y152365D01*
G01X67824Y157760D02*
X73162Y152639D01*
G01X67956Y157861D02*
X73115Y152912D01*
G01X68192Y157861D02*
X73066Y153185D01*
G01X68429Y157861D02*
X73019Y153458D01*
G01X68666Y157861D02*
X72971Y153731D01*
G01X68903Y157861D02*
X72923Y154005D01*
G01X69140Y157861D02*
X72875Y154278D01*
G01X69377Y157861D02*
X72827Y154550D01*
G01X69613Y157861D02*
X72780Y154824D01*
G01X69851Y157861D02*
X72731Y155097D01*
G01X70087Y157861D02*
X72684Y155370D01*
G01X70324Y157861D02*
X72636Y155643D01*
G01X70561Y157861D02*
X72588Y155916D01*
G01X70798Y157861D02*
X72540Y156190D01*
G01X71035Y157861D02*
X72492Y156463D01*
G01X71271Y157861D02*
X72445Y156735D01*
G01X71508Y157861D02*
X72396Y157009D01*
G01X71745Y157861D02*
X72348Y157282D01*
G01X71982Y157861D02*
X72301Y157555D01*
G01X72219Y157861D02*
X72253Y157828D01*
G01X64213Y155999D02*
X64275Y156165D01*
G01X64213Y155999D02*
X64150Y155831D01*
G01X64275Y156165D02*
X64338Y156332D01*
G01D02*
X64401Y156499D01*
G01X64150Y155831D02*
X64087Y155664D01*
G01X63961Y155331D02*
X63898Y155163D01*
G01X64024Y155498D02*
X63961Y155331D01*
G01X64087Y155664D02*
X64024Y155498D01*
G01X63898Y155163D02*
X63836Y154996D01*
G01X63333Y153661D02*
X63270Y153494D01*
G01X63647Y154496D02*
X63584Y154329D01*
G01X63710Y154663D02*
X63647Y154496D01*
G01X63773Y154830D02*
X63710Y154663D01*
G01X63584Y154329D02*
X63521Y154162D01*
G01X63396Y153828D02*
X63333Y153661D01*
G01X63836Y154996D02*
X63773Y154830D01*
G01X63521Y154162D02*
X63459Y153995D01*
G01D02*
X63396Y153828D01*
G01X73066Y153185D02*
X73115Y152912D01*
G01X69377Y157861D02*
X69613D01*
G01X69140D02*
X69377D01*
G01X69851D02*
X70087D01*
G01D02*
X70324D01*
G01X68192D02*
X68429D01*
G01X68903D02*
X69140D01*
G01X68429D02*
X68666D01*
G01D02*
X68903D01*
G01X71271D02*
X71508D01*
G01D02*
X71745D01*
G01D02*
X71982D01*
G01D02*
X72219D01*
G01X70561D02*
X70798D01*
G01X71035D02*
X71271D01*
G01X67956D02*
X68192D01*
G01X70798D02*
X71035D01*
G01X70324D02*
X70561D01*
G01X68496Y153934D02*
X68448Y154207D01*
G01X68544Y153661D02*
X68496Y153934D01*
G01X68352Y154754D02*
X68304Y155028D01*
G01X67824Y157760D02*
X67806Y157861D01*
X67956D01*
G01X68400Y154481D02*
X68352Y154754D01*
G01X68736Y152569D02*
X68688Y152841D01*
G01X68640Y153114D02*
X68592Y153388D01*
G01D02*
X68544Y153661D01*
G01X68688Y152841D02*
X68640Y153114D01*
G01X68448Y154207D02*
X68400Y154481D01*
G01X68015Y156667D02*
X67967Y156941D01*
G01D02*
X67920Y157214D01*
G01X68304Y155028D02*
X68256Y155300D01*
G01X67920Y157214D02*
X67872Y157487D01*
G01D02*
X67824Y157760D01*
G01X68208Y155574D02*
X68160Y155847D01*
G01X68256Y155300D02*
X68208Y155574D01*
G01X68064Y156393D02*
X68015Y156667D01*
G01X68112Y156121D02*
X68064Y156393D01*
G01X68160Y155847D02*
X68112Y156121D01*
G01X69613Y157861D02*
X69851D01*
G01X68736Y152569D02*
X68784Y152295D01*
G01X72301Y157555D02*
X72253Y157828D01*
G01X72396Y157009D02*
X72348Y157282D01*
G01X72219Y157861D02*
X72247D01*
X72253Y157828D01*
G01X72588Y155916D02*
X72540Y156190D01*
G01X72492Y156463D02*
X72445Y156735D01*
G01D02*
X72396Y157009D01*
G01X72540Y156190D02*
X72492Y156463D01*
G01X72636Y155643D02*
X72588Y155916D01*
G01X72348Y157282D02*
X72301Y157555D01*
G01X73162Y152639D02*
X73210Y152365D01*
G01X72684Y155370D02*
X72636Y155643D01*
G01X72827Y154550D02*
X72875Y154278D01*
G01X72780Y154824D02*
X72827Y154550D01*
G01X72731Y155097D02*
X72684Y155370D01*
G01X72731Y155097D02*
X72780Y154824D01*
G01X72923Y154005D02*
X72971Y153731D01*
G01X73115Y152912D02*
X73162Y152639D01*
G01X73019Y153458D02*
X73066Y153185D01*
G01X72971Y153731D02*
X73019Y153458D01*
G01X72875Y154278D02*
X72923Y154005D01*
G01X81666Y141074D02*
X77753Y144827D01*
G01X81842Y141132D02*
X77974Y144843D01*
G01X81999Y141209D02*
X78175Y144876D01*
G01X82138Y141303D02*
X78361Y144925D01*
G01X82277Y141396D02*
X78547Y144974D01*
G01X82415Y141491D02*
X78710Y145045D01*
G01X82554Y141585D02*
X78858Y145130D01*
G01X82693Y141678D02*
X79007Y145215D01*
G01X85184Y138522D02*
X85176Y138529D01*
G01X82831Y141773D02*
X79131Y145323D01*
G01X85507Y138438D02*
X85312Y138625D01*
G01X85830Y138357D02*
X85449Y138722D01*
G01X82949Y141887D02*
X79240Y145446D01*
G01X83052Y142016D02*
X79348Y145568D01*
G01X86152Y138274D02*
X85586Y138818D01*
G01X83155Y142144D02*
X79439Y145708D01*
G01X86475Y138191D02*
X85722Y138914D01*
G01X86798Y138110D02*
X85859Y139011D01*
G01X83258Y142273D02*
X79509Y145869D01*
G01X83361Y142401D02*
X79579Y146029D01*
G01X87121Y138026D02*
X85995Y139107D01*
G01X87443Y137944D02*
X86131Y139203D01*
G01X83463Y142530D02*
X79642Y146195D01*
G01X83567Y142658D02*
X79675Y146392D01*
G01X87767Y137862D02*
X86267Y139299D01*
G01X88041Y137825D02*
X86404Y139396D01*
G01X83646Y142810D02*
X79708Y146588D01*
G01X88208Y137893D02*
X86540Y139493D01*
G01X83714Y142971D02*
X79740Y146783D01*
G01X83783Y143132D02*
X79748Y147003D01*
G01X88376Y137958D02*
X86676Y139588D01*
G01X83851Y143294D02*
X79746Y147232D01*
G01X88544Y138026D02*
X86812Y139686D01*
G01X88711Y138091D02*
X86949Y139782D01*
G01X83920Y143455D02*
X79744Y147461D01*
G01X83988Y143617D02*
X79742Y147690D01*
G01X88879Y138157D02*
X87085Y139879D01*
G01X89047Y138224D02*
X87221Y139975D01*
G01X84057Y143778D02*
X79708Y147950D01*
G01X89215Y138289D02*
X87358Y140071D01*
G01X84098Y143966D02*
X79675Y148209D01*
G01X84133Y144160D02*
X79641Y148469D01*
G01X89383Y138357D02*
X87494Y140169D01*
G01X84167Y144354D02*
X79607Y148729D01*
G01X89551Y138422D02*
X87630Y140264D01*
G01X89719Y138487D02*
X87766Y140361D01*
G01X84203Y144547D02*
X79559Y149001D01*
G01X84237Y144741D02*
X79511Y149275D01*
G01X89888Y138553D02*
X87902Y140458D01*
G01X90056Y138619D02*
X88039Y140554D01*
G01X84272Y144935D02*
X79464Y149548D01*
G01X84306Y145129D02*
X79415Y149821D01*
G01X90225Y138685D02*
X88175Y140652D01*
G01X84308Y145355D02*
X79367Y150095D01*
G01X90393Y138750D02*
X88311Y140747D01*
G01X90562Y138815D02*
X88447Y140844D01*
G01X84310Y145581D02*
X79319Y150368D01*
G01X84312Y145806D02*
X79272Y150641D01*
G01X90731Y138880D02*
X88583Y140941D01*
G01X90900Y138945D02*
X88719Y141037D01*
G01X84313Y146032D02*
X79224Y150914D01*
G01X84315Y146257D02*
X79175Y151187D01*
G01X91069Y139011D02*
X88855Y141134D01*
G01X91238Y139076D02*
X88991Y141231D01*
G01X84317Y146483D02*
X79128Y151460D01*
G01X91408Y139141D02*
X89128Y141327D01*
G01X79080Y151734D02*
X84309Y146718D01*
G01X91577Y139205D02*
X89264Y141424D01*
G01X79032Y152007D02*
X84277Y146975D01*
G01X91748Y139268D02*
X89400Y141520D01*
G01X78983Y152280D02*
X84246Y147232D01*
G01X78936Y152554D02*
X84215Y147489D01*
G01X89536Y141617D02*
X91918Y139333D01*
G01X78888Y152827D02*
X84184Y147747D01*
G01X92088Y139397D02*
X89672Y141714D01*
G01X78840Y153100D02*
X84152Y148004D01*
G01X92258Y139461D02*
X87185Y144327D01*
G01X78792Y153373D02*
X84121Y148261D01*
G01X92429Y139523D02*
X86895Y144833D01*
G01X78744Y153646D02*
X84078Y148529D01*
G01X92600Y139587D02*
X86646Y145299D01*
G01X92772Y139649D02*
X86499Y145667D01*
G01X92944Y139712D02*
X86353Y146034D01*
G01X93116Y139773D02*
X86225Y146384D01*
G01X93290Y139834D02*
X86148Y146685D01*
G01X93464Y139895D02*
X86071Y146987D01*
G01X93640Y139952D02*
X85994Y147287D01*
G01X93817Y140009D02*
X85925Y147581D01*
G01X94000Y140063D02*
X85889Y147843D01*
G01X94200Y140097D02*
X85852Y148105D01*
G01X94430Y140104D02*
X85816Y148367D01*
G01X94660Y140109D02*
X85780Y148628D01*
G01X94890Y140117D02*
X85744Y148890D01*
G01X95120Y140123D02*
X85735Y149127D01*
G01X95351Y140130D02*
X85725Y149363D01*
G01X95581Y140136D02*
X85715Y149599D01*
G01X95806Y140147D02*
X85705Y149837D01*
G01X96021Y140168D02*
X85695Y150074D01*
G01X96237Y140188D02*
X85685Y150310D01*
G01X96453Y140208D02*
X85689Y150533D01*
G01X96668Y140229D02*
X85698Y150753D01*
G01X96884Y140249D02*
X85713Y150965D01*
G01X97100Y140269D02*
X85734Y151173D01*
G01X97304Y140299D02*
X85754Y151380D01*
G01X85780Y151582D02*
X97505Y140334D01*
G01X85813Y151778D02*
X91752Y146080D01*
G01X85845Y151974D02*
X91391Y146655D01*
G01X85879Y152170D02*
X91211Y147054D01*
G01X85916Y152361D02*
X91031Y147454D01*
G01X85962Y152544D02*
X90943Y147766D01*
G01X86007Y152727D02*
X90867Y148065D01*
G01X86054Y152910D02*
X90791Y148365D01*
G01X86798Y138110D02*
X86475Y138191D01*
G01X85184Y138522D02*
X85507Y138438D01*
G01X87121Y138026D02*
X86798Y138110D01*
G01X87443Y137944D02*
X87121Y138026D01*
G01X85830Y138357D02*
X85507Y138438D01*
G01X86475Y138191D02*
X86152Y138274D01*
G01D02*
X85830Y138357D01*
G01X87767Y137862D02*
X87443Y137944D01*
G01X84030Y148803D02*
X84078Y148529D01*
G01X81666Y141074D02*
X77753Y144827D01*
G01X81842Y141132D02*
X77974Y144843D01*
G01X81999Y141209D02*
X78175Y144876D01*
G01X82138Y141303D02*
X78361Y144925D01*
G01X82277Y141396D02*
X78547Y144974D01*
G01X82415Y141491D02*
X78710Y145045D01*
G01X82554Y141585D02*
X78858Y145130D01*
G01X82693Y141678D02*
X79007Y145215D01*
G01X85184Y138522D02*
X85176Y138529D01*
G01X82831Y141773D02*
X79131Y145323D01*
G01X85507Y138438D02*
X85312Y138625D01*
G01X85830Y138357D02*
X85449Y138722D01*
G01X82949Y141887D02*
X79240Y145446D01*
G01X83052Y142016D02*
X79348Y145568D01*
G01X86152Y138274D02*
X85586Y138818D01*
G01X83155Y142144D02*
X79439Y145708D01*
G01X86475Y138191D02*
X85722Y138914D01*
G01X86798Y138110D02*
X85859Y139011D01*
G01X83258Y142273D02*
X79509Y145869D01*
G01X83361Y142401D02*
X79579Y146029D01*
G01X87121Y138026D02*
X85995Y139107D01*
G01X87443Y137944D02*
X86131Y139203D01*
G01X83463Y142530D02*
X79642Y146195D01*
G01X83567Y142658D02*
X79675Y146392D01*
G01X87767Y137862D02*
X86267Y139299D01*
G01X88041Y137825D02*
X86404Y139396D01*
G01X83646Y142810D02*
X79708Y146588D01*
G01X88208Y137893D02*
X86540Y139493D01*
G01X83714Y142971D02*
X79740Y146783D01*
G01X83783Y143132D02*
X79748Y147003D01*
G01X88376Y137958D02*
X86676Y139588D01*
G01X83851Y143294D02*
X79746Y147232D01*
G01X88544Y138026D02*
X86812Y139686D01*
G01X88711Y138091D02*
X86949Y139782D01*
G01X83920Y143455D02*
X79744Y147461D01*
G01X83988Y143617D02*
X79742Y147690D01*
G01X88879Y138157D02*
X87085Y139879D01*
G01X89047Y138224D02*
X87221Y139975D01*
G01X84057Y143778D02*
X79708Y147950D01*
G01X89215Y138289D02*
X87358Y140071D01*
G01X84098Y143966D02*
X79675Y148209D01*
G01X84133Y144160D02*
X79641Y148469D01*
G01X89383Y138357D02*
X87494Y140169D01*
G01X84167Y144354D02*
X79607Y148729D01*
G01X89551Y138422D02*
X87630Y140264D01*
G01X89719Y138487D02*
X87766Y140361D01*
G01X84203Y144547D02*
X79559Y149001D01*
G01X84237Y144741D02*
X79511Y149275D01*
G01X89888Y138553D02*
X87902Y140458D01*
G01X90056Y138619D02*
X88039Y140554D01*
G01X84272Y144935D02*
X79464Y149548D01*
G01X84306Y145129D02*
X79415Y149821D01*
G01X90225Y138685D02*
X88175Y140652D01*
G01X84308Y145355D02*
X79367Y150095D01*
G01X90393Y138750D02*
X88311Y140747D01*
G01X90562Y138815D02*
X88447Y140844D01*
G01X84310Y145581D02*
X79319Y150368D01*
G01X84312Y145806D02*
X79272Y150641D01*
G01X90731Y138880D02*
X88583Y140941D01*
G01X90900Y138945D02*
X88719Y141037D01*
G01X84313Y146032D02*
X79224Y150914D01*
G01X84315Y146257D02*
X79175Y151187D01*
G01X91069Y139011D02*
X88855Y141134D01*
G01X91238Y139076D02*
X88991Y141231D01*
G01X84317Y146483D02*
X79128Y151460D01*
G01X91408Y139141D02*
X89128Y141327D01*
G01X79080Y151734D02*
X84309Y146718D01*
G01X91577Y139205D02*
X89264Y141424D01*
G01X79032Y152007D02*
X84277Y146975D01*
G01X91748Y139268D02*
X89400Y141520D01*
G01X78983Y152280D02*
X84246Y147232D01*
G01X78936Y152554D02*
X84215Y147489D01*
G01X89536Y141617D02*
X91918Y139333D01*
G01X78888Y152827D02*
X84184Y147747D01*
G01X92088Y139397D02*
X89672Y141714D01*
G01X78840Y153100D02*
X84152Y148004D01*
G01X92258Y139461D02*
X87185Y144327D01*
G01X78792Y153373D02*
X84121Y148261D01*
G01X92429Y139523D02*
X86895Y144833D01*
G01X78744Y153646D02*
X84078Y148529D01*
G01X92600Y139587D02*
X86646Y145299D01*
G01X92772Y139649D02*
X86499Y145667D01*
G01X92944Y139712D02*
X86353Y146034D01*
G01X93116Y139773D02*
X86225Y146384D01*
G01X93290Y139834D02*
X86148Y146685D01*
G01X93464Y139895D02*
X86071Y146987D01*
G01X93640Y139952D02*
X85994Y147287D01*
G01X93817Y140009D02*
X85925Y147581D01*
G01X94000Y140063D02*
X85889Y147843D01*
G01X94200Y140097D02*
X85852Y148105D01*
G01X94430Y140104D02*
X85816Y148367D01*
G01X94660Y140109D02*
X85780Y148628D01*
G01X94890Y140117D02*
X85744Y148890D01*
G01X95120Y140123D02*
X85735Y149127D01*
G01X95351Y140130D02*
X85725Y149363D01*
G01X95581Y140136D02*
X85715Y149599D01*
G01X95806Y140147D02*
X85705Y149837D01*
G01X96021Y140168D02*
X85695Y150074D01*
G01X96237Y140188D02*
X85685Y150310D01*
G01X96453Y140208D02*
X85689Y150533D01*
G01X96668Y140229D02*
X85698Y150753D01*
G01X96884Y140249D02*
X85713Y150965D01*
G01X97100Y140269D02*
X85734Y151173D01*
G01X97304Y140299D02*
X85754Y151380D01*
G01X85780Y151582D02*
X97505Y140334D01*
G01X85813Y151778D02*
X91752Y146080D01*
G01X85845Y151974D02*
X91391Y146655D01*
G01X85879Y152170D02*
X91211Y147054D01*
G01X85916Y152361D02*
X91031Y147454D01*
G01X85962Y152544D02*
X90943Y147766D01*
G01X86007Y152727D02*
X90867Y148065D01*
G01X86054Y152910D02*
X90791Y148365D01*
G01X86798Y138110D02*
X86475Y138191D01*
G01X85184Y138522D02*
X85507Y138438D01*
G01X87121Y138026D02*
X86798Y138110D01*
G01X87443Y137944D02*
X87121Y138026D01*
G01X85830Y138357D02*
X85507Y138438D01*
G01X86475Y138191D02*
X86152Y138274D01*
G01D02*
X85830Y138357D01*
G01X87767Y137862D02*
X87443Y137944D01*
G01X84030Y148803D02*
X84078Y148529D01*
G01X78696Y153919D02*
X84030Y148803D01*
G01X78648Y154193D02*
X83982Y149076D01*
G01X78600Y154466D02*
X83934Y149349D01*
G01X78552Y154739D02*
X83886Y149623D01*
G01X78504Y155013D02*
X83838Y149896D01*
G01X78456Y155285D02*
X83790Y150169D01*
G01X78408Y155559D02*
X83742Y150442D01*
G01X78360Y155832D02*
X83694Y150715D01*
G01X78312Y156106D02*
X83647Y150988D01*
G01X78265Y156378D02*
X83598Y151262D01*
G01X78216Y156651D02*
X83550Y151535D01*
G01X78168Y156925D02*
X83503Y151808D01*
G01X78121Y157198D02*
X83455Y152082D01*
G01X86100Y153093D02*
X90728Y148653D01*
G01X86152Y153270D02*
X90708Y148900D01*
G01X86212Y153440D02*
X90688Y149146D01*
G01X86271Y153610D02*
X90668Y149393D01*
G01X86332Y153780D02*
X90648Y149639D01*
G01X86391Y153950D02*
X90644Y149870D01*
G01X86451Y154119D02*
X90662Y150080D01*
G01X86524Y154277D02*
X90679Y150291D01*
G01X86599Y154432D02*
X90697Y150501D01*
G01X86674Y154587D02*
X90715Y150712D01*
G01X86749Y154743D02*
X90732Y150922D01*
G01X86823Y154898D02*
X90763Y151119D01*
G01X86899Y155053D02*
X90811Y151301D01*
G01X86985Y155198D02*
X90858Y151483D01*
G01X87076Y155338D02*
X90905Y151665D01*
G01X87167Y155477D02*
X90953Y151846D01*
G01X87259Y155617D02*
X91000Y152027D01*
G01X79415Y149821D02*
X79367Y150095D01*
G01X79559Y149001D02*
X79511Y149275D01*
G01X79367Y150095D02*
X79319Y150368D01*
G01X79607Y148729D02*
X79559Y149001D01*
G01X79464Y149548D02*
X79415Y149821D01*
G01X79224Y150914D02*
X79175Y151187D01*
G01X79272Y150641D02*
X79224Y150914D01*
G01X79319Y150368D02*
X79272Y150641D01*
G01X79128Y151460D02*
X79080Y151734D01*
G01D02*
X79032Y152007D01*
G01D02*
X78983Y152280D01*
G01X79511Y149275D02*
X79464Y149548D01*
G01X83790Y150169D02*
X83838Y149896D01*
G01X83647Y150988D02*
X83694Y150715D01*
G01D02*
X83742Y150442D01*
G01X83503Y151808D02*
X83550Y151535D01*
G01D02*
X83598Y151262D01*
G01D02*
X83647Y150988D01*
G01X83742Y150442D02*
X83790Y150169D01*
G01X83838Y149896D02*
X83886Y149623D01*
G01D02*
X83934Y149349D01*
G01X83455Y152082D02*
X83503Y151808D01*
G01X83406Y152354D02*
X83455Y152082D01*
G01X83934Y149349D02*
X83982Y149076D01*
G01X79128Y151460D02*
X79175Y151187D01*
G01X83982Y149076D02*
X84030Y148803D01*
G01X78696Y153919D02*
X84030Y148803D01*
G01X78648Y154193D02*
X83982Y149076D01*
G01X78600Y154466D02*
X83934Y149349D01*
G01X78552Y154739D02*
X83886Y149623D01*
G01X78504Y155013D02*
X83838Y149896D01*
G01X78456Y155285D02*
X83790Y150169D01*
G01X78408Y155559D02*
X83742Y150442D01*
G01X78360Y155832D02*
X83694Y150715D01*
G01X78312Y156106D02*
X83647Y150988D01*
G01X78265Y156378D02*
X83598Y151262D01*
G01X78216Y156651D02*
X83550Y151535D01*
G01X78168Y156925D02*
X83503Y151808D01*
G01X78121Y157198D02*
X83455Y152082D01*
G01X86100Y153093D02*
X90728Y148653D01*
G01X86152Y153270D02*
X90708Y148900D01*
G01X86212Y153440D02*
X90688Y149146D01*
G01X86271Y153610D02*
X90668Y149393D01*
G01X86332Y153780D02*
X90648Y149639D01*
G01X86391Y153950D02*
X90644Y149870D01*
G01X86451Y154119D02*
X90662Y150080D01*
G01X86524Y154277D02*
X90679Y150291D01*
G01X86599Y154432D02*
X90697Y150501D01*
G01X86674Y154587D02*
X90715Y150712D01*
G01X86749Y154743D02*
X90732Y150922D01*
G01X86823Y154898D02*
X90763Y151119D01*
G01X86899Y155053D02*
X90811Y151301D01*
G01X86985Y155198D02*
X90858Y151483D01*
G01X87076Y155338D02*
X90905Y151665D01*
G01X87167Y155477D02*
X90953Y151846D01*
G01X87259Y155617D02*
X91000Y152027D01*
G01X79415Y149821D02*
X79367Y150095D01*
G01X79559Y149001D02*
X79511Y149275D01*
G01X79367Y150095D02*
X79319Y150368D01*
G01X79607Y148729D02*
X79559Y149001D01*
G01X79464Y149548D02*
X79415Y149821D01*
G01X79224Y150914D02*
X79175Y151187D01*
G01X79272Y150641D02*
X79224Y150914D01*
G01X79319Y150368D02*
X79272Y150641D01*
G01X79128Y151460D02*
X79080Y151734D01*
G01D02*
X79032Y152007D01*
G01D02*
X78983Y152280D01*
G01X79511Y149275D02*
X79464Y149548D01*
G01X83790Y150169D02*
X83838Y149896D01*
G01X83647Y150988D02*
X83694Y150715D01*
G01D02*
X83742Y150442D01*
G01X83503Y151808D02*
X83550Y151535D01*
G01D02*
X83598Y151262D01*
G01D02*
X83647Y150988D01*
G01X83742Y150442D02*
X83790Y150169D01*
G01X83838Y149896D02*
X83886Y149623D01*
G01D02*
X83934Y149349D01*
G01X83455Y152082D02*
X83503Y151808D01*
G01X83406Y152354D02*
X83455Y152082D01*
G01X83934Y149349D02*
X83982Y149076D01*
G01X79128Y151460D02*
X79175Y151187D01*
G01X83982Y149076D02*
X84030Y148803D01*
G01X78073Y157472D02*
X83406Y152354D01*
G01X78025Y157744D02*
X83358Y152628D01*
G01X78140Y157861D02*
X83311Y152901D01*
G01X78377Y157861D02*
X83263Y153175D01*
G01X78614Y157861D02*
X83215Y153447D01*
G01X78851Y157861D02*
X83167Y153720D01*
G01X79088Y157861D02*
X83119Y153994D01*
G01X79325Y157861D02*
X83071Y154267D01*
G01X79561Y157861D02*
X83023Y154541D01*
G01X79798Y157861D02*
X82975Y154813D01*
G01X80035Y157861D02*
X82927Y155087D01*
G01X80272Y157861D02*
X82879Y155360D01*
G01X80509Y157861D02*
X82831Y155633D01*
G01X80745Y157861D02*
X82783Y155906D01*
G01X80983Y157861D02*
X82735Y156180D01*
G01X81219Y157861D02*
X82687Y156453D01*
G01X81456Y157861D02*
X82639Y156726D01*
G01X81693Y157861D02*
X82591Y156999D01*
G01X81930Y157861D02*
X82543Y157272D01*
G01X82167Y157861D02*
X82495Y157546D01*
G01X82403Y157861D02*
X82448Y157819D01*
G01X87350Y155757D02*
X91050Y152207D01*
G01X87442Y155896D02*
X91123Y152364D01*
G01X87533Y156035D02*
X91195Y152522D01*
G01X87641Y156159D02*
X91268Y152680D01*
G01X87751Y156281D02*
X91341Y152837D01*
G01X87860Y156403D02*
X91414Y152994D01*
G01X87970Y156525D02*
X91486Y153152D01*
G01X88080Y156647D02*
X91572Y153297D01*
G01X88190Y156768D02*
X91668Y153432D01*
G01X88300Y156890D02*
X91764Y153567D01*
G01X88420Y157002D02*
X91860Y153702D01*
G01X88545Y157110D02*
X91956Y153837D01*
G01X88671Y157217D02*
X92052Y153972D01*
G01X88795Y157324D02*
X92148Y154108D01*
G01X88921Y157430D02*
X92266Y154222D01*
G01X89046Y157537D02*
X92385Y154334D01*
G01X89179Y157638D02*
X92504Y154448D01*
G01X89316Y157733D02*
X92624Y154560D01*
G01X89453Y157828D02*
X92742Y154674D01*
G01X89590Y157924D02*
X92862Y154786D01*
G01X89728Y158020D02*
X92994Y154886D01*
G01X89865Y158115D02*
X93138Y154976D01*
G01X90012Y158201D02*
X93282Y155064D01*
G01X90162Y158285D02*
X93426Y155154D01*
G01X90312Y158368D02*
X93570Y155243D01*
G01X90462Y158452D02*
X93715Y155331D01*
G01X90612Y158535D02*
X93871Y155409D01*
G01X90763Y158616D02*
X94044Y155470D01*
G01X90928Y158687D02*
X94218Y155530D01*
G01X91091Y158757D02*
X94392Y155591D01*
G01X91254Y158827D02*
X94565Y155651D01*
G01X91418Y158898D02*
X94738Y155713D01*
G01X91581Y158968D02*
X94943Y155744D01*
G01X91755Y159029D02*
X95155Y155767D01*
G01X91933Y159086D02*
X95367Y155791D01*
G01X92111Y159142D02*
X95578Y155816D01*
G01X92289Y159198D02*
X95791Y155839D01*
G01X92467Y159255D02*
X96053Y155815D01*
G01X79088Y157861D02*
X79325D01*
G01D02*
X79561D01*
G01X80035D02*
X80272D01*
G01X79561D02*
X79798D01*
G01D02*
X80035D01*
G01X78140D02*
X78377D01*
G01D02*
X78614D01*
G01X78851D02*
X79088D01*
G01X78614D02*
X78851D01*
G01X78025Y157744D02*
X78004Y157861D01*
X78140D01*
G01X81930D02*
X82167D01*
G01X80272D02*
X80509D01*
G01X82167D02*
X82403D01*
G01X81693D02*
X81930D01*
G01X80509D02*
X80745D01*
G01D02*
X80983D01*
G01D02*
X81219D01*
G01X81456D02*
X81693D01*
G01X81219D02*
X81456D01*
G01X78744Y153646D02*
X78696Y153919D01*
G01X78648Y154193D02*
X78600Y154466D01*
G01X78792Y153373D02*
X78744Y153646D01*
G01X78696Y153919D02*
X78648Y154193D01*
G01X78840Y153100D02*
X78792Y153373D01*
G01X78983Y152280D02*
X78936Y152554D01*
G01X78073Y157472D02*
X78025Y157744D01*
G01X78888Y152827D02*
X78840Y153100D01*
G01X78600Y154466D02*
X78552Y154739D01*
G01X78936Y152554D02*
X78888Y152827D01*
G01X78216Y156651D02*
X78168Y156925D01*
G01X78265Y156378D02*
X78216Y156651D01*
G01X78121Y157198D02*
X78073Y157472D01*
G01X78168Y156925D02*
X78121Y157198D01*
G01X78456Y155285D02*
X78408Y155559D01*
G01X78552Y154739D02*
X78504Y155013D01*
G01D02*
X78456Y155285D01*
G01X78360Y155832D02*
X78312Y156106D01*
G01D02*
X78265Y156378D01*
G01X78408Y155559D02*
X78360Y155832D01*
G01X82687Y156453D02*
X82639Y156726D01*
G01X82591Y156999D02*
X82543Y157272D01*
G01X82639Y156726D02*
X82591Y156999D01*
G01X82735Y156180D02*
X82687Y156453D01*
G01X82543Y157272D02*
X82495Y157546D01*
G01X82879Y155360D02*
X82927Y155087D01*
G01X82783Y155906D02*
X82735Y156180D01*
G01X82831Y155633D02*
X82783Y155906D01*
G01X82879Y155360D02*
X82831Y155633D01*
G01X82403Y157861D02*
X82440D01*
X82448Y157819D01*
G01X82927Y155087D02*
X82975Y154813D01*
G01X82495Y157546D02*
X82448Y157819D01*
G01X82975Y154813D02*
X83023Y154541D01*
G01X83119Y153994D02*
X83167Y153720D01*
G01D02*
X83215Y153447D01*
G01X83023Y154541D02*
X83071Y154267D01*
G01D02*
X83119Y153994D01*
G01X83215Y153447D02*
X83263Y153175D01*
G01X83358Y152628D02*
X83406Y152354D01*
G01X83263Y153175D02*
X83311Y152901D01*
G01D02*
X83358Y152628D01*
G01X78073Y157472D02*
X83406Y152354D01*
G01X78025Y157744D02*
X83358Y152628D01*
G01X78140Y157861D02*
X83311Y152901D01*
G01X78377Y157861D02*
X83263Y153175D01*
G01X78614Y157861D02*
X83215Y153447D01*
G01X78851Y157861D02*
X83167Y153720D01*
G01X79088Y157861D02*
X83119Y153994D01*
G01X79325Y157861D02*
X83071Y154267D01*
G01X79561Y157861D02*
X83023Y154541D01*
G01X79798Y157861D02*
X82975Y154813D01*
G01X80035Y157861D02*
X82927Y155087D01*
G01X80272Y157861D02*
X82879Y155360D01*
G01X80509Y157861D02*
X82831Y155633D01*
G01X80745Y157861D02*
X82783Y155906D01*
G01X80983Y157861D02*
X82735Y156180D01*
G01X81219Y157861D02*
X82687Y156453D01*
G01X81456Y157861D02*
X82639Y156726D01*
G01X81693Y157861D02*
X82591Y156999D01*
G01X81930Y157861D02*
X82543Y157272D01*
G01X82167Y157861D02*
X82495Y157546D01*
G01X82403Y157861D02*
X82448Y157819D01*
G01X87350Y155757D02*
X91050Y152207D01*
G01X87442Y155896D02*
X91123Y152364D01*
G01X87533Y156035D02*
X91195Y152522D01*
G01X87641Y156159D02*
X91268Y152680D01*
G01X87751Y156281D02*
X91341Y152837D01*
G01X87860Y156403D02*
X91414Y152994D01*
G01X87970Y156525D02*
X91486Y153152D01*
G01X88080Y156647D02*
X91572Y153297D01*
G01X88190Y156768D02*
X91668Y153432D01*
G01X88300Y156890D02*
X91764Y153567D01*
G01X88420Y157002D02*
X91860Y153702D01*
G01X88545Y157110D02*
X91956Y153837D01*
G01X88671Y157217D02*
X92052Y153972D01*
G01X88795Y157324D02*
X92148Y154108D01*
G01X88921Y157430D02*
X92266Y154222D01*
G01X89046Y157537D02*
X92385Y154334D01*
G01X89179Y157638D02*
X92504Y154448D01*
G01X89316Y157733D02*
X92624Y154560D01*
G01X89453Y157828D02*
X92742Y154674D01*
G01X89590Y157924D02*
X92862Y154786D01*
G01X89728Y158020D02*
X92994Y154886D01*
G01X89865Y158115D02*
X93138Y154976D01*
G01X90012Y158201D02*
X93282Y155064D01*
G01X90162Y158285D02*
X93426Y155154D01*
G01X90312Y158368D02*
X93570Y155243D01*
G01X90462Y158452D02*
X93715Y155331D01*
G01X90612Y158535D02*
X93871Y155409D01*
G01X90763Y158616D02*
X94044Y155470D01*
G01X90928Y158687D02*
X94218Y155530D01*
G01X91091Y158757D02*
X94392Y155591D01*
G01X91254Y158827D02*
X94565Y155651D01*
G01X91418Y158898D02*
X94738Y155713D01*
G01X91581Y158968D02*
X94943Y155744D01*
G01X91755Y159029D02*
X95155Y155767D01*
G01X91933Y159086D02*
X95367Y155791D01*
G01X92111Y159142D02*
X95578Y155816D01*
G01X92289Y159198D02*
X95791Y155839D01*
G01X92467Y159255D02*
X96053Y155815D01*
G01X79088Y157861D02*
X79325D01*
G01D02*
X79561D01*
G01X80035D02*
X80272D01*
G01X79561D02*
X79798D01*
G01D02*
X80035D01*
G01X78140D02*
X78377D01*
G01D02*
X78614D01*
G01X78851D02*
X79088D01*
G01X78614D02*
X78851D01*
G01X78025Y157744D02*
X78004Y157861D01*
X78140D01*
G01X81930D02*
X82167D01*
G01X80272D02*
X80509D01*
G01X82167D02*
X82403D01*
G01X81693D02*
X81930D01*
G01X80509D02*
X80745D01*
G01D02*
X80983D01*
G01D02*
X81219D01*
G01X81456D02*
X81693D01*
G01X81219D02*
X81456D01*
G01X78744Y153646D02*
X78696Y153919D01*
G01X78648Y154193D02*
X78600Y154466D01*
G01X78792Y153373D02*
X78744Y153646D01*
G01X78696Y153919D02*
X78648Y154193D01*
G01X78840Y153100D02*
X78792Y153373D01*
G01X78983Y152280D02*
X78936Y152554D01*
G01X78073Y157472D02*
X78025Y157744D01*
G01X78888Y152827D02*
X78840Y153100D01*
G01X78600Y154466D02*
X78552Y154739D01*
G01X78936Y152554D02*
X78888Y152827D01*
G01X78216Y156651D02*
X78168Y156925D01*
G01X78265Y156378D02*
X78216Y156651D01*
G01X78121Y157198D02*
X78073Y157472D01*
G01X78168Y156925D02*
X78121Y157198D01*
G01X78456Y155285D02*
X78408Y155559D01*
G01X78552Y154739D02*
X78504Y155013D01*
G01D02*
X78456Y155285D01*
G01X78360Y155832D02*
X78312Y156106D01*
G01D02*
X78265Y156378D01*
G01X78408Y155559D02*
X78360Y155832D01*
G01X82687Y156453D02*
X82639Y156726D01*
G01X82591Y156999D02*
X82543Y157272D01*
G01X82639Y156726D02*
X82591Y156999D01*
G01X82735Y156180D02*
X82687Y156453D01*
G01X82543Y157272D02*
X82495Y157546D01*
G01X82879Y155360D02*
X82927Y155087D01*
G01X82783Y155906D02*
X82735Y156180D01*
G01X82831Y155633D02*
X82783Y155906D01*
G01X82879Y155360D02*
X82831Y155633D01*
G01X82403Y157861D02*
X82440D01*
X82448Y157819D01*
G01X82927Y155087D02*
X82975Y154813D01*
G01X82495Y157546D02*
X82448Y157819D01*
G01X82975Y154813D02*
X83023Y154541D01*
G01X83119Y153994D02*
X83167Y153720D01*
G01D02*
X83215Y153447D01*
G01X83023Y154541D02*
X83071Y154267D01*
G01D02*
X83119Y153994D01*
G01X83215Y153447D02*
X83263Y153175D01*
G01X83358Y152628D02*
X83406Y152354D01*
G01X83263Y153175D02*
X83311Y152901D01*
G01D02*
X83358Y152628D01*
G01X98505Y140512D02*
X94864Y144005D01*
G01X98689Y140562D02*
X95131Y143975D01*
G01X98872Y140614D02*
X95399Y143946D01*
G01X99057Y140664D02*
X95667Y143916D01*
G01X99241Y140714D02*
X95905Y143915D01*
G01X99425Y140766D02*
X96114Y143941D01*
G01X99609Y140816D02*
X96324Y143967D01*
G01X99784Y140876D02*
X96534Y143993D01*
G01X99951Y140942D02*
X96744Y144019D01*
G01X100119Y141008D02*
X96938Y144060D01*
G01X100286Y141075D02*
X97106Y144125D01*
G01X100454Y141141D02*
X97275Y144191D01*
G01X100621Y141208D02*
X97443Y144256D01*
G01X100789Y141274D02*
X97612Y144322D01*
G01X100940Y141356D02*
X97781Y144387D01*
G01X101091Y141439D02*
X97934Y144468D01*
G01X101242Y141521D02*
X98073Y144562D01*
G01X101393Y141604D02*
X98211Y144656D01*
G01X101544Y141687D02*
X98350Y144750D01*
G01X101695Y141769D02*
X98489Y144844D01*
G01X101840Y141857D02*
X98628Y144938D01*
G01X101975Y141955D02*
X98762Y145036D01*
G01X102109Y142053D02*
X98877Y145153D01*
G01X102244Y142150D02*
X98992Y145271D01*
G01X102379Y142249D02*
X99106Y145388D01*
G01X102513Y142346D02*
X99220Y145505D01*
G01X102648Y142445D02*
X99335Y145623D01*
G01X102774Y142551D02*
X99449Y145740D01*
G01X102893Y142665D02*
X99552Y145869D01*
G01X103012Y142777D02*
X99645Y146007D01*
G01X103131Y142890D02*
X99737Y146146D01*
G01X103250Y143003D02*
X99830Y146284D01*
G01X103369Y143116D02*
X99923Y146422D01*
G01X103489Y143229D02*
X100015Y146561D01*
G01X103596Y143354D02*
X100108Y146699D01*
G01X103697Y143483D02*
X100182Y146856D01*
G01X103799Y143613D02*
X100252Y147015D01*
G01X103900Y143743D02*
X100323Y147174D01*
G01X104001Y143873D02*
X100394Y147334D01*
G01X104103Y144003D02*
X100465Y147493D01*
G01X104204Y144133D02*
X100536Y147652D01*
G01X104296Y144272D02*
X100597Y147820D01*
G01X104378Y144420D02*
X100644Y148002D01*
G01X104461Y144568D02*
X100691Y148186D01*
G01X104544Y144716D02*
X100737Y148368D01*
G01X104626Y144864D02*
X100783Y148550D01*
G01X104709Y145012D02*
X100830Y148733D01*
G01X104791Y145160D02*
X100868Y148924D01*
G01X104861Y145321D02*
X100884Y149136D01*
G01X104926Y145485D02*
X100901Y149347D01*
G01X104992Y145649D02*
X100917Y149558D01*
G01X105058Y145813D02*
X100933Y149770D01*
G01X105124Y145977D02*
X100950Y149981D01*
G01X105189Y146142D02*
X100931Y150226D01*
G01X105246Y146314D02*
X100905Y150478D01*
G01X105297Y146493D02*
X100878Y150731D01*
G01X105348Y146671D02*
X100852Y150984D01*
G01X105398Y146850D02*
X100825Y151237D01*
G01X105449Y147029D02*
X100738Y151548D01*
G01X105499Y147208D02*
X100642Y151867D01*
G01X105537Y147399D02*
X100545Y152187D01*
G01X105574Y147591D02*
X100400Y152554D01*
G01X105611Y147782D02*
X100164Y153007D01*
G01X105648Y147974D02*
X99851Y153534D01*
G01X93836Y159533D02*
X105684Y148167D01*
G01X94045Y159558D02*
X105709Y148370D01*
G01X94255Y159584D02*
X105733Y148573D01*
G01X98505Y140512D02*
X94864Y144005D01*
G01X98689Y140562D02*
X95131Y143975D01*
G01X98872Y140614D02*
X95399Y143946D01*
G01X99057Y140664D02*
X95667Y143916D01*
G01X99241Y140714D02*
X95905Y143915D01*
G01X99425Y140766D02*
X96114Y143941D01*
G01X99609Y140816D02*
X96324Y143967D01*
G01X99784Y140876D02*
X96534Y143993D01*
G01X99951Y140942D02*
X96744Y144019D01*
G01X100119Y141008D02*
X96938Y144060D01*
G01X100286Y141075D02*
X97106Y144125D01*
G01X100454Y141141D02*
X97275Y144191D01*
G01X100621Y141208D02*
X97443Y144256D01*
G01X100789Y141274D02*
X97612Y144322D01*
G01X100940Y141356D02*
X97781Y144387D01*
G01X101091Y141439D02*
X97934Y144468D01*
G01X101242Y141521D02*
X98073Y144562D01*
G01X101393Y141604D02*
X98211Y144656D01*
G01X101544Y141687D02*
X98350Y144750D01*
G01X101695Y141769D02*
X98489Y144844D01*
G01X101840Y141857D02*
X98628Y144938D01*
G01X101975Y141955D02*
X98762Y145036D01*
G01X102109Y142053D02*
X98877Y145153D01*
G01X102244Y142150D02*
X98992Y145271D01*
G01X102379Y142249D02*
X99106Y145388D01*
G01X102513Y142346D02*
X99220Y145505D01*
G01X102648Y142445D02*
X99335Y145623D01*
G01X102774Y142551D02*
X99449Y145740D01*
G01X102893Y142665D02*
X99552Y145869D01*
G01X103012Y142777D02*
X99645Y146007D01*
G01X103131Y142890D02*
X99737Y146146D01*
G01X103250Y143003D02*
X99830Y146284D01*
G01X103369Y143116D02*
X99923Y146422D01*
G01X103489Y143229D02*
X100015Y146561D01*
G01X103596Y143354D02*
X100108Y146699D01*
G01X103697Y143483D02*
X100182Y146856D01*
G01X103799Y143613D02*
X100252Y147015D01*
G01X103900Y143743D02*
X100323Y147174D01*
G01X104001Y143873D02*
X100394Y147334D01*
G01X104103Y144003D02*
X100465Y147493D01*
G01X104204Y144133D02*
X100536Y147652D01*
G01X104296Y144272D02*
X100597Y147820D01*
G01X104378Y144420D02*
X100644Y148002D01*
G01X104461Y144568D02*
X100691Y148186D01*
G01X104544Y144716D02*
X100737Y148368D01*
G01X104626Y144864D02*
X100783Y148550D01*
G01X104709Y145012D02*
X100830Y148733D01*
G01X104791Y145160D02*
X100868Y148924D01*
G01X104861Y145321D02*
X100884Y149136D01*
G01X104926Y145485D02*
X100901Y149347D01*
G01X104992Y145649D02*
X100917Y149558D01*
G01X105058Y145813D02*
X100933Y149770D01*
G01X105124Y145977D02*
X100950Y149981D01*
G01X105189Y146142D02*
X100931Y150226D01*
G01X105246Y146314D02*
X100905Y150478D01*
G01X105297Y146493D02*
X100878Y150731D01*
G01X105348Y146671D02*
X100852Y150984D01*
G01X105398Y146850D02*
X100825Y151237D01*
G01X105449Y147029D02*
X100738Y151548D01*
G01X105499Y147208D02*
X100642Y151867D01*
G01X105537Y147399D02*
X100545Y152187D01*
G01X105574Y147591D02*
X100400Y152554D01*
G01X105611Y147782D02*
X100164Y153007D01*
G01X105648Y147974D02*
X99851Y153534D01*
G01X93836Y159533D02*
X105684Y148167D01*
G01X94045Y159558D02*
X105709Y148370D01*
G01X94255Y159584D02*
X105733Y148573D01*
G01X94465Y159611D02*
X105758Y148777D01*
G01X94685Y159627D02*
X105784Y148980D01*
G01X94913Y159636D02*
X105797Y149194D01*
G01X95140Y159645D02*
X105811Y149408D01*
G01X95368Y159653D02*
X105825Y149621D01*
G01X95595Y159662D02*
X105832Y149843D01*
G01X95841Y159653D02*
X105836Y150065D01*
G01X96089Y159643D02*
X105831Y150297D01*
G01X96338Y159631D02*
X105820Y150535D01*
G01X96587Y159620D02*
X105809Y150773D01*
G01X96835Y159609D02*
X105798Y151011D01*
G01X97112Y159570D02*
X105764Y151270D01*
G01X97390Y159531D02*
X105727Y151533D01*
G01X97668Y159492D02*
X105690Y151796D01*
G01X97945Y159453D02*
X105636Y152075D01*
G01X94465Y159611D02*
X105758Y148777D01*
G01X94685Y159627D02*
X105784Y148980D01*
G01X94913Y159636D02*
X105797Y149194D01*
G01X95140Y159645D02*
X105811Y149408D01*
G01X95368Y159653D02*
X105825Y149621D01*
G01X95595Y159662D02*
X105832Y149843D01*
G01X95841Y159653D02*
X105836Y150065D01*
G01X96089Y159643D02*
X105831Y150297D01*
G01X96338Y159631D02*
X105820Y150535D01*
G01X96587Y159620D02*
X105809Y150773D01*
G01X96835Y159609D02*
X105798Y151011D01*
G01X97112Y159570D02*
X105764Y151270D01*
G01X97390Y159531D02*
X105727Y151533D01*
G01X97668Y159492D02*
X105690Y151796D01*
G01X97945Y159453D02*
X105636Y152075D01*
G01X97705Y140370D02*
X93251Y144643D01*
G01X97905Y140405D02*
X93818Y144326D01*
G01X98105Y140440D02*
X94188Y144199D01*
G01X98306Y140475D02*
X94559Y144070D01*
G01X97705Y140370D02*
X93251Y144643D01*
G01X97905Y140405D02*
X93818Y144326D01*
G01X98105Y140440D02*
X94188Y144199D01*
G01X98306Y140475D02*
X94559Y144070D01*
G01X98257Y159381D02*
X105566Y152369D01*
G01X98573Y159304D02*
X105496Y152663D01*
G01X98891Y159227D02*
X105400Y152983D01*
G01X99237Y159123D02*
X105286Y153319D01*
G01X99610Y158991D02*
X105168Y153660D01*
G01X99985Y158859D02*
X104989Y154058D01*
G01X100440Y158650D02*
X104808Y154459D01*
G01X100908Y158429D02*
X104525Y154958D01*
G01X101536Y158053D02*
X104145Y155550D01*
G01X98257Y159381D02*
X105566Y152369D01*
G01X98573Y159304D02*
X105496Y152663D01*
G01X98891Y159227D02*
X105400Y152983D01*
G01X99237Y159123D02*
X105286Y153319D01*
G01X99610Y158991D02*
X105168Y153660D01*
G01X99985Y158859D02*
X104989Y154058D01*
G01X100440Y158650D02*
X104808Y154459D01*
G01X100908Y158429D02*
X104525Y154958D01*
G01X101536Y158053D02*
X104145Y155550D01*
G01X92652Y159305D02*
X96322Y155784D01*
G01X92845Y159347D02*
X96592Y155753D01*
G01X93039Y159388D02*
X96902Y155682D01*
G01X93232Y159430D02*
X97271Y155556D01*
G01X93425Y159472D02*
X97639Y155429D01*
G01X93625Y159507D02*
X98233Y155087D01*
G01X92652Y159305D02*
X96322Y155784D01*
G01X92845Y159347D02*
X96592Y155753D01*
G01X93039Y159388D02*
X96902Y155682D01*
G01X93232Y159430D02*
X97271Y155556D01*
G01X93425Y159472D02*
X97639Y155429D01*
G01X93625Y159507D02*
X98233Y155087D01*
G01X111614Y189721D02*
Y183422D01*
G02X99016I-6299J0D01*
G01Y189721D01*
G02X111614I6299J0D01*
G01X99016D02*
G02X111614I6299J0D01*
G01Y183422D01*
G02X99016I-6299J0D01*
G01Y189721D01*
G01D02*
Y183422D01*
G03X111614I6299J0D01*
G01Y189721D01*
G03X99016I-6299J0D01*
G01X97835Y213343D02*
G02X112795I7480J0D01*
G02X97835I-7480J0D01*
G01X112795D02*
G02X97835I-7480J0D01*
G02X112795I7480J0D01*
G01D02*
G03X97835I-7480J0D01*
G03X112795I7480J0D01*
G01X141693Y-609436D02*
Y-684436D01*
G01Y-659436D02*
X244693D01*
Y-634436D01*
G01X141693D02*
X244693D01*
G01X242913Y424016D02*
G02X229528I-6693J0D01*
G02X242913I6692J0D01*
G01X229528D02*
G02X242913I6692J0D01*
G02X229528I-6693J0D01*
G01D02*
G02X242913I6692J0D01*
G02X229528I-6693J0D01*
G01X246693Y-609436D02*
Y-684436D01*
G01X244693Y-609436D02*
Y-684436D01*
G01X252200Y-669436D02*
Y-664436D01*
X253466D01*
X253973Y-664686D01*
X254353Y-665019D01*
X254670Y-665519D01*
X254923Y-666103D01*
X254986Y-666936D01*
X254923Y-667769D01*
X254670Y-668353D01*
X254353Y-668853D01*
X253973Y-669186D01*
X253466Y-669436D01*
X252200D01*
G01X257110D02*
X258693Y-664436D01*
X260276Y-669436D01*
G01X259706Y-667686D02*
X257680D01*
G01X263793Y-664436D02*
Y-669436D01*
G01X262336Y-664436D02*
X265250D01*
G01X270160Y-669436D02*
X267626D01*
Y-664436D01*
X270160D01*
G01X269146Y-666853D02*
X267626D01*
G01X273993Y-669603D02*
X273866Y-669519D01*
Y-669353D01*
X273993Y-669269D01*
X274120Y-669353D01*
Y-669519D01*
X273993Y-669603D01*
G01Y-667353D02*
X273866Y-667269D01*
Y-667103D01*
X273993Y-667019D01*
X274120Y-667103D01*
Y-667269D01*
X273993Y-667353D01*
G01X246693Y-659436D02*
X446693D01*
G01X252326Y-644436D02*
Y-639436D01*
X253846D01*
X254353Y-639686D01*
X254733Y-640269D01*
X254860Y-640936D01*
X254733Y-641603D01*
X254416Y-642103D01*
X253846Y-642353D01*
X252326D01*
G01X257553Y-644603D02*
X259833Y-639436D01*
G01X262336Y-644436D02*
Y-639436D01*
X265250Y-644436D01*
Y-639436D01*
G01X268893Y-644603D02*
X268766Y-644519D01*
Y-644353D01*
X268893Y-644269D01*
X269020Y-644353D01*
Y-644519D01*
X268893Y-644603D01*
G01Y-642353D02*
X268766Y-642269D01*
Y-642103D01*
X268893Y-642019D01*
X269020Y-642103D01*
Y-642269D01*
X268893Y-642353D01*
G01X246693Y-634436D02*
X446693D01*
G01X252326Y-619436D02*
Y-614436D01*
X253846D01*
X254353Y-614686D01*
X254733Y-615269D01*
X254860Y-615936D01*
X254733Y-616603D01*
X254416Y-617103D01*
X253846Y-617353D01*
X252326D01*
G01X257426Y-619436D02*
Y-614436D01*
X259010D01*
X259516Y-614686D01*
X259833Y-615019D01*
X259960Y-615686D01*
X259833Y-616353D01*
X259453Y-616769D01*
X259010Y-617019D01*
X257426D01*
G01X259010D02*
X259960Y-619436D01*
G01X263793D02*
X263286Y-619353D01*
X262843Y-619019D01*
X262463Y-618519D01*
X262210Y-617936D01*
X262083Y-617269D01*
Y-616603D01*
X262210Y-615936D01*
X262463Y-615353D01*
X262843Y-614853D01*
X263286Y-614519D01*
X263793Y-614436D01*
X264300Y-614519D01*
X264743Y-614853D01*
X265123Y-615353D01*
X265376Y-615936D01*
X265503Y-616603D01*
Y-617269D01*
X265376Y-617936D01*
X265123Y-618519D01*
X264743Y-619019D01*
X264300Y-619353D01*
X263793Y-619436D01*
G01X267626Y-618436D02*
X267943Y-618936D01*
X268323Y-619269D01*
X268766Y-619436D01*
X269273Y-619269D01*
X269653Y-618936D01*
X270033Y-618436D01*
X270160Y-617769D01*
Y-614436D01*
G01X275260Y-619436D02*
X272726D01*
Y-614436D01*
X275260D01*
G01X274246Y-616853D02*
X272726D01*
G01X280486Y-614853D02*
X280106Y-614603D01*
X279663Y-614436D01*
X279156D01*
X278586Y-614686D01*
X278143Y-615103D01*
X277826Y-615603D01*
X277573Y-616436D01*
X277510Y-617186D01*
X277636Y-617936D01*
X277826Y-618436D01*
X278206Y-618936D01*
X278650Y-619269D01*
X279093Y-619436D01*
X279536D01*
X279980Y-619269D01*
X280360Y-619019D01*
X280676Y-618686D01*
G01X284193Y-614436D02*
Y-619436D01*
G01X282736Y-614436D02*
X285650D01*
G01X289293Y-619603D02*
X289166Y-619519D01*
Y-619353D01*
X289293Y-619269D01*
X289420Y-619353D01*
Y-619519D01*
X289293Y-619603D01*
G01Y-617353D02*
X289166Y-617269D01*
Y-617103D01*
X289293Y-617019D01*
X289420Y-617103D01*
Y-617269D01*
X289293Y-617353D01*
G01X307874Y424016D02*
G02X294488I-6693J0D01*
G02X307874I6693J0D01*
G01X294488D02*
G02X307874I6693J0D01*
G02X294488I-6693J0D01*
G01D02*
G02X307874I6693J0D01*
G02X294488I-6693J0D01*
G01X339764Y46417D02*
G02X327165I-6299J0D01*
G02X339764I6299J0D01*
G01X327165D02*
G02X339764I6299J0D01*
G02X327165I-6299J0D01*
G01D02*
G02X339764I6299J0D01*
G02X327165I-6299J0D01*
G01X336476Y89331D02*
G02X324154I-6161J0D01*
G02X336476I6161J0D01*
G01X324154D02*
G02X336476I6161J0D01*
G02X324154I-6161J0D01*
G01D02*
G02X336476I6161J0D01*
G02X324154I-6161J0D01*
G01X361693Y-659436D02*
Y-684436D01*
G01X364326Y-661936D02*
Y-666936D01*
X366860D01*
G01X369933Y-661936D02*
X371453D01*
G01X370693D02*
Y-666936D01*
G01X369933D02*
X371453D01*
G01X376300Y-664269D02*
X376553Y-664019D01*
X376743Y-663603D01*
X376870Y-663019D01*
X376743Y-662519D01*
X376490Y-662186D01*
X376046Y-661936D01*
X374336D01*
Y-666936D01*
X376426D01*
X376870Y-666603D01*
X377123Y-666103D01*
X377250Y-665519D01*
X377123Y-664936D01*
X376743Y-664436D01*
X376300Y-664269D01*
X374336D01*
G01X380893Y-667103D02*
X380766Y-667019D01*
Y-666853D01*
X380893Y-666769D01*
X381020Y-666853D01*
Y-667019D01*
X380893Y-667103D01*
G01Y-664853D02*
X380766Y-664769D01*
Y-664603D01*
X380893Y-664519D01*
X381020Y-664603D01*
Y-664769D01*
X380893Y-664853D01*
G01X404693Y-659436D02*
Y-684436D01*
G01Y-634436D02*
Y-659436D01*
G01X412706Y-687603D02*
X412813Y-687478D01*
X412893Y-687269D01*
X412946Y-686978D01*
X412893Y-686728D01*
X412786Y-686561D01*
X412600Y-686436D01*
X411880D01*
Y-688936D01*
X412760D01*
X412946Y-688769D01*
X413053Y-688519D01*
X413106Y-688228D01*
X413053Y-687936D01*
X412893Y-687686D01*
X412706Y-687603D01*
X411880D01*
G01X415173Y-688936D02*
Y-687269D01*
G01Y-687561D02*
X415066Y-687394D01*
X414906Y-687311D01*
X414720Y-687269D01*
X414533Y-687353D01*
X414373Y-687519D01*
X414266Y-687769D01*
X414213Y-688103D01*
X414266Y-688436D01*
X414373Y-688686D01*
X414533Y-688853D01*
X414720Y-688936D01*
X414906Y-688894D01*
X415066Y-688769D01*
X415173Y-688603D01*
G01X416493Y-688644D02*
X416626Y-688811D01*
X416813Y-688936D01*
X416973D01*
X417133Y-688853D01*
X417240Y-688728D01*
X417293Y-688561D01*
X417266Y-688311D01*
X417160Y-688186D01*
X416680Y-687936D01*
X416573Y-687644D01*
X416626Y-687436D01*
X416733Y-687311D01*
X416893Y-687269D01*
X417053Y-687311D01*
X417213Y-687436D01*
G01X418693Y-687811D02*
X419546D01*
X419466Y-687519D01*
X419333Y-687353D01*
X419146Y-687269D01*
X418960Y-687311D01*
X418800Y-687436D01*
X418693Y-687728D01*
X418640Y-687978D01*
Y-688228D01*
X418693Y-688478D01*
X418826Y-688728D01*
X418986Y-688894D01*
X419173Y-688936D01*
X419360Y-688853D01*
X419546Y-688603D01*
G01X420813Y-688936D02*
Y-686436D01*
G01Y-687686D02*
X420946Y-687436D01*
X421106Y-687311D01*
X421266Y-687269D01*
X421506Y-687353D01*
X421666Y-687519D01*
X421773Y-687811D01*
Y-688144D01*
X421720Y-688478D01*
X421613Y-688728D01*
X421426Y-688894D01*
X421266Y-688936D01*
X421106Y-688894D01*
X420946Y-688769D01*
X420813Y-688561D01*
G01X423493Y-688936D02*
X423333Y-688894D01*
X423173Y-688728D01*
X423066Y-688436D01*
X423013Y-688103D01*
X423066Y-687769D01*
X423173Y-687478D01*
X423333Y-687311D01*
X423493Y-687269D01*
X423653Y-687311D01*
X423813Y-687478D01*
X423920Y-687769D01*
X423946Y-688103D01*
X423920Y-688436D01*
X423813Y-688728D01*
X423653Y-688894D01*
X423493Y-688936D01*
G01X426173D02*
Y-687269D01*
G01Y-687561D02*
X426066Y-687394D01*
X425906Y-687311D01*
X425720Y-687269D01*
X425533Y-687353D01*
X425373Y-687519D01*
X425266Y-687769D01*
X425213Y-688103D01*
X425266Y-688436D01*
X425373Y-688686D01*
X425533Y-688853D01*
X425720Y-688936D01*
X425906Y-688894D01*
X426066Y-688769D01*
X426173Y-688603D01*
G01X427520Y-688936D02*
Y-687269D01*
G01Y-687603D02*
X427653Y-687436D01*
X427786Y-687311D01*
X427973Y-687269D01*
X428106Y-687311D01*
X428266Y-687436D01*
G01X430573Y-686436D02*
Y-688936D01*
G01Y-688561D02*
X430466Y-688769D01*
X430306Y-688894D01*
X430120Y-688936D01*
X429906Y-688853D01*
X429746Y-688644D01*
X429640Y-688394D01*
X429613Y-688103D01*
X429640Y-687811D01*
X429746Y-687561D01*
X429906Y-687353D01*
X430120Y-687269D01*
X430306Y-687311D01*
X430440Y-687394D01*
X430573Y-687561D01*
G01X433960Y-688936D02*
Y-686436D01*
X434626D01*
X434840Y-686561D01*
X434973Y-686728D01*
X435026Y-687061D01*
X434973Y-687394D01*
X434813Y-687603D01*
X434626Y-687728D01*
X433960D01*
G01X434626D02*
X435026Y-688936D01*
G01X436293Y-687811D02*
X437146D01*
X437066Y-687519D01*
X436933Y-687353D01*
X436746Y-687269D01*
X436560Y-687311D01*
X436400Y-687436D01*
X436293Y-687728D01*
X436240Y-687978D01*
Y-688228D01*
X436293Y-688478D01*
X436426Y-688728D01*
X436586Y-688894D01*
X436773Y-688936D01*
X436960Y-688853D01*
X437146Y-688603D01*
G01X438413Y-687269D02*
X438893Y-688936D01*
X439373Y-687269D01*
G01X441093Y-689019D02*
X441040Y-688978D01*
Y-688894D01*
X441093Y-688853D01*
X441146Y-688894D01*
Y-688978D01*
X441093Y-689019D01*
G01X443613Y-688936D02*
Y-686436D01*
X442626Y-688228D01*
X443960D01*
G01X444826Y-688936D02*
X445493Y-686436D01*
X446160Y-688936D01*
G01X445920Y-688061D02*
X445066D01*
G01X408593Y-661936D02*
Y-666936D01*
G01X407136Y-661936D02*
X410050D01*
G01X413693Y-666936D02*
X413313Y-666853D01*
X412933Y-666519D01*
X412680Y-665936D01*
X412553Y-665269D01*
X412680Y-664603D01*
X412933Y-664019D01*
X413313Y-663686D01*
X413693Y-663603D01*
X414073Y-663686D01*
X414453Y-664019D01*
X414706Y-664603D01*
X414770Y-665269D01*
X414706Y-665936D01*
X414453Y-666519D01*
X414073Y-666853D01*
X413693Y-666936D01*
G01X418793D02*
X418413Y-666853D01*
X418033Y-666519D01*
X417780Y-665936D01*
X417653Y-665269D01*
X417780Y-664603D01*
X418033Y-664019D01*
X418413Y-663686D01*
X418793Y-663603D01*
X419173Y-663686D01*
X419553Y-664019D01*
X419806Y-664603D01*
X419870Y-665269D01*
X419806Y-665936D01*
X419553Y-666519D01*
X419173Y-666853D01*
X418793Y-666936D01*
G01X423893D02*
Y-661936D01*
G01X428993Y-667103D02*
X428866Y-667019D01*
Y-666853D01*
X428993Y-666769D01*
X429120Y-666853D01*
Y-667019D01*
X428993Y-667103D01*
G01Y-664853D02*
X428866Y-664769D01*
Y-664603D01*
X428993Y-664519D01*
X429120Y-664603D01*
Y-664769D01*
X428993Y-664853D01*
G01X407326Y-641936D02*
Y-636936D01*
X408910D01*
X409416Y-637186D01*
X409733Y-637519D01*
X409860Y-638186D01*
X409733Y-638853D01*
X409353Y-639269D01*
X408910Y-639519D01*
X407326D01*
G01X408910D02*
X409860Y-641936D01*
G01X414960D02*
X412426D01*
Y-636936D01*
X414960D01*
G01X413946Y-639353D02*
X412426D01*
G01X417210Y-636936D02*
X418793Y-641936D01*
X420376Y-636936D01*
G01X423893Y-642103D02*
X423766Y-642019D01*
Y-641853D01*
X423893Y-641769D01*
X424020Y-641853D01*
Y-642019D01*
X423893Y-642103D01*
G01Y-639853D02*
X423766Y-639769D01*
Y-639603D01*
X423893Y-639519D01*
X424020Y-639603D01*
Y-639769D01*
X423893Y-639853D01*
G01X2010999Y-388000D02*
Y1475775D01*
X-407000D01*
Y-386798D01*
Y-755294D01*
Y-793716D01*
X-368578D01*
X1942346D01*
X2010999D01*
Y-725063D01*
Y-388000D01*
G01X-67097Y237990D02*
Y241090D01*
X-67863D01*
X-68170Y240935D01*
X-68400Y240728D01*
X-68592Y240418D01*
X-68745Y240057D01*
X-68783Y239540D01*
X-68745Y239023D01*
X-68592Y238662D01*
X-68400Y238352D01*
X-68170Y238145D01*
X-67863Y237990D01*
X-67097D01*
G01X-71347Y239643D02*
X-71500Y239798D01*
X-71615Y240057D01*
X-71692Y240418D01*
X-71615Y240728D01*
X-71462Y240935D01*
X-71193Y241090D01*
X-70158D01*
Y237990D01*
X-71423D01*
X-71692Y238197D01*
X-71845Y238507D01*
X-71922Y238868D01*
X-71845Y239230D01*
X-71615Y239540D01*
X-71347Y239643D01*
X-70158D01*
G01X-73297Y238610D02*
X-73527Y238248D01*
X-73833Y238042D01*
X-74178Y237990D01*
X-74485Y238042D01*
X-74792Y238300D01*
X-74983Y238610D01*
X-75022Y238920D01*
X-74945Y239282D01*
X-74677Y239540D01*
X-74408Y239643D01*
X-74063D01*
G01X-74408D02*
X-74638Y239798D01*
X-74830Y240057D01*
X-74907Y240367D01*
X-74830Y240677D01*
X-74638Y240935D01*
X-74293Y241090D01*
X-73948Y241038D01*
X-73603Y240832D01*
G01X-63007Y372000D02*
Y375100D01*
X-63773D01*
X-64080Y374945D01*
X-64310Y374738D01*
X-64502Y374428D01*
X-64655Y374067D01*
X-64693Y373550D01*
X-64655Y373033D01*
X-64502Y372672D01*
X-64310Y372362D01*
X-64080Y372155D01*
X-63773Y372000D01*
X-63007D01*
G01X-67257Y373653D02*
X-67410Y373808D01*
X-67525Y374067D01*
X-67602Y374428D01*
X-67525Y374738D01*
X-67372Y374945D01*
X-67103Y375100D01*
X-66068D01*
Y372000D01*
X-67333D01*
X-67602Y372207D01*
X-67755Y372517D01*
X-67832Y372878D01*
X-67755Y373240D01*
X-67525Y373550D01*
X-67257Y373653D01*
X-66068D01*
G01X-69322Y374583D02*
X-69552Y374893D01*
X-69820Y375048D01*
X-70127Y375100D01*
X-70510Y374997D01*
X-70778Y374738D01*
X-70855Y374428D01*
X-70817Y374118D01*
X-70663Y373860D01*
X-69897Y373343D01*
X-69552Y372982D01*
X-69322Y372465D01*
X-69245Y372000D01*
X-70855D01*
G01X-69213Y244716D02*
X-42987D01*
X-56100Y279292D01*
X-69213Y244716D01*
G01X-69113Y377216D02*
X-42887D01*
X-56000Y411792D01*
X-69113Y377216D01*
G01X-42602Y-671096D02*
X-41975Y-671621D01*
X-41270Y-671936D01*
X-40644D01*
X-40017Y-671621D01*
X-39547Y-671096D01*
X-39312Y-670361D01*
X-39469Y-669626D01*
X-39860Y-668996D01*
X-40565Y-668576D01*
X-41505Y-668366D01*
X-42054Y-667946D01*
X-42289Y-667211D01*
X-42132Y-666476D01*
X-41740Y-665951D01*
X-41192Y-665636D01*
X-40644D01*
X-40095Y-665846D01*
X-39625Y-666371D01*
G01X-36302Y-671936D02*
Y-665636D01*
G01X-33012D02*
Y-671936D01*
G01Y-668786D02*
X-36302D01*
G01X-29297Y-665636D02*
X-27417D01*
G01X-28357D02*
Y-671936D01*
G01X-29297D02*
X-27417D01*
G01X-20490D02*
X-23624D01*
Y-665636D01*
X-20490D01*
G01X-21744Y-668681D02*
X-23624D01*
G01X-17559Y-671936D02*
Y-665636D01*
X-13955Y-671936D01*
Y-665636D01*
G01X-9614Y-673091D02*
X-9300Y-671726D01*
G01X-3157Y-665636D02*
Y-671936D01*
G01X-4959Y-665636D02*
X-1355D01*
G01X1185Y-671936D02*
X3143Y-665636D01*
X5101Y-671936D01*
G01X4396Y-669731D02*
X1890D01*
G01X8503Y-665636D02*
X10383D01*
G01X9443D02*
Y-671936D01*
G01X8503D02*
X10383D01*
G01X13393Y-665636D02*
X14490Y-671936D01*
X15743Y-665636D01*
X16996Y-671936D01*
X18093Y-665636D01*
G01X20085Y-671936D02*
X22043Y-665636D01*
X24001Y-671936D01*
G01X23296Y-669731D02*
X20790D01*
G01X26541Y-671936D02*
Y-665636D01*
X30145Y-671936D01*
Y-665636D01*
G01X39376Y-671936D02*
Y-665636D01*
X41335D01*
X41961Y-665951D01*
X42353Y-666371D01*
X42510Y-667211D01*
X42353Y-668051D01*
X41883Y-668576D01*
X41335Y-668891D01*
X39376D01*
G01X41335D02*
X42510Y-671936D01*
G01X47243Y-672146D02*
X47086Y-672041D01*
Y-671831D01*
X47243Y-671726D01*
X47400Y-671831D01*
Y-672041D01*
X47243Y-672146D01*
G01X53543Y-671936D02*
X52916Y-671831D01*
X52368Y-671411D01*
X51898Y-670781D01*
X51585Y-670046D01*
X51428Y-669206D01*
Y-668366D01*
X51585Y-667526D01*
X51898Y-666791D01*
X52368Y-666161D01*
X52916Y-665741D01*
X53543Y-665636D01*
X54170Y-665741D01*
X54718Y-666161D01*
X55188Y-666791D01*
X55501Y-667526D01*
X55658Y-668366D01*
Y-669206D01*
X55501Y-670046D01*
X55188Y-670781D01*
X54718Y-671411D01*
X54170Y-671831D01*
X53543Y-671936D01*
G01X59843Y-672146D02*
X59686Y-672041D01*
Y-671831D01*
X59843Y-671726D01*
X60000Y-671831D01*
Y-672041D01*
X59843Y-672146D01*
G01X67866Y-666161D02*
X67396Y-665846D01*
X66848Y-665636D01*
X66221D01*
X65516Y-665951D01*
X64968Y-666476D01*
X64576Y-667106D01*
X64263Y-668156D01*
X64185Y-669101D01*
X64341Y-670046D01*
X64576Y-670676D01*
X65046Y-671306D01*
X65595Y-671726D01*
X66143Y-671936D01*
X66691D01*
X67240Y-671726D01*
X67710Y-671411D01*
X68101Y-670991D01*
G01X72443Y-672146D02*
X72286Y-672041D01*
Y-671831D01*
X72443Y-671726D01*
X72600Y-671831D01*
Y-672041D01*
X72443Y-672146D01*
G01X-42680Y-661936D02*
Y-655636D01*
G01X-39704D02*
X-42680Y-659521D01*
G01X-39234Y-661936D02*
X-41349Y-657736D01*
G01X-36380Y-655636D02*
Y-660151D01*
X-36067Y-661096D01*
X-35440Y-661726D01*
X-34657Y-661936D01*
X-33874Y-661726D01*
X-33247Y-661096D01*
X-32934Y-660151D01*
Y-655636D01*
G01X-26790Y-661936D02*
X-29924D01*
Y-655636D01*
X-26790D01*
G01X-28044Y-658681D02*
X-29924D01*
G01X-22997Y-655636D02*
X-21117D01*
G01X-22057D02*
Y-661936D01*
G01X-22997D02*
X-21117D01*
G01X-11102Y-661096D02*
X-10475Y-661621D01*
X-9770Y-661936D01*
X-9144D01*
X-8517Y-661621D01*
X-8047Y-661096D01*
X-7812Y-660361D01*
X-7969Y-659626D01*
X-8360Y-658996D01*
X-9065Y-658576D01*
X-10005Y-658366D01*
X-10554Y-657946D01*
X-10789Y-657211D01*
X-10632Y-656476D01*
X-10240Y-655951D01*
X-9692Y-655636D01*
X-9144D01*
X-8595Y-655846D01*
X-8125Y-656371D01*
G01X-4802Y-661936D02*
Y-655636D01*
G01X-1512D02*
Y-661936D01*
G01Y-658786D02*
X-4802D01*
G01X1185Y-661936D02*
X3143Y-655636D01*
X5101Y-661936D01*
G01X4396Y-659731D02*
X1890D01*
G01X7641Y-661936D02*
Y-655636D01*
X11245Y-661936D01*
Y-655636D01*
G01X20398Y-661936D02*
Y-655636D01*
G01X23688D02*
Y-661936D01*
G01Y-658786D02*
X20398D01*
G01X26698Y-661096D02*
X27325Y-661621D01*
X28030Y-661936D01*
X28656D01*
X29283Y-661621D01*
X29753Y-661096D01*
X29988Y-660361D01*
X29831Y-659626D01*
X29440Y-658996D01*
X28735Y-658576D01*
X27795Y-658366D01*
X27246Y-657946D01*
X27011Y-657211D01*
X27168Y-656476D01*
X27560Y-655951D01*
X28108Y-655636D01*
X28656D01*
X29205Y-655846D01*
X29675Y-656371D01*
G01X33703Y-655636D02*
X35583D01*
G01X34643D02*
Y-661936D01*
G01X33703D02*
X35583D01*
G01X38985D02*
X40943Y-655636D01*
X42901Y-661936D01*
G01X42196Y-659731D02*
X39690D01*
G01X45441Y-661936D02*
Y-655636D01*
X49045Y-661936D01*
Y-655636D01*
G01X54013Y-658786D02*
X55580D01*
Y-660676D01*
X55110Y-661306D01*
X54561Y-661726D01*
X53778Y-661936D01*
X52995Y-661726D01*
X52446Y-661306D01*
X51976Y-660676D01*
X51663Y-659941D01*
X51506Y-659101D01*
Y-658366D01*
X51663Y-657736D01*
X51976Y-657001D01*
X52446Y-656371D01*
X52916Y-655951D01*
X53543Y-655636D01*
X54091D01*
X54718Y-655846D01*
X55188Y-656266D01*
G01X59686Y-663091D02*
X60000Y-661726D01*
G01X66143Y-655636D02*
Y-661936D01*
G01X64341Y-655636D02*
X67945D01*
G01X70485Y-661936D02*
X72443Y-655636D01*
X74401Y-661936D01*
G01X73696Y-659731D02*
X71190D01*
G01X78743Y-661936D02*
X78116Y-661831D01*
X77568Y-661411D01*
X77098Y-660781D01*
X76785Y-660046D01*
X76628Y-659206D01*
Y-658366D01*
X76785Y-657526D01*
X77098Y-656791D01*
X77568Y-656161D01*
X78116Y-655741D01*
X78743Y-655636D01*
X79370Y-655741D01*
X79918Y-656161D01*
X80388Y-656791D01*
X80701Y-657526D01*
X80858Y-658366D01*
Y-659206D01*
X80701Y-660046D01*
X80388Y-660781D01*
X79918Y-661411D01*
X79370Y-661831D01*
X78743Y-661936D01*
G01X91343D02*
Y-659101D01*
X89776Y-655636D01*
G01X92910D02*
X91343Y-659101D01*
G01X95920Y-655636D02*
Y-660151D01*
X96233Y-661096D01*
X96860Y-661726D01*
X97643Y-661936D01*
X98426Y-661726D01*
X99053Y-661096D01*
X99366Y-660151D01*
Y-655636D01*
G01X101985Y-661936D02*
X103943Y-655636D01*
X105901Y-661936D01*
G01X105196Y-659731D02*
X102690D01*
G01X108441Y-661936D02*
Y-655636D01*
X112045Y-661936D01*
Y-655636D01*
G01X-42759Y-651936D02*
Y-645636D01*
X-39155Y-651936D01*
Y-645636D01*
G01X-34657Y-651936D02*
X-35284Y-651831D01*
X-35832Y-651411D01*
X-36302Y-650781D01*
X-36615Y-650046D01*
X-36772Y-649206D01*
Y-648366D01*
X-36615Y-647526D01*
X-36302Y-646791D01*
X-35832Y-646161D01*
X-35284Y-645741D01*
X-34657Y-645636D01*
X-34030Y-645741D01*
X-33482Y-646161D01*
X-33012Y-646791D01*
X-32699Y-647526D01*
X-32542Y-648366D01*
Y-649206D01*
X-32699Y-650046D01*
X-33012Y-650781D01*
X-33482Y-651411D01*
X-34030Y-651831D01*
X-34657Y-651936D01*
G01X-28357Y-652146D02*
X-28514Y-652041D01*
Y-651831D01*
X-28357Y-651726D01*
X-28200Y-651831D01*
Y-652041D01*
X-28357Y-652146D01*
G01X-22057Y-651936D02*
Y-645636D01*
X-22997Y-646896D01*
G01Y-651936D02*
X-21117D01*
G01X-15757D02*
X-15209Y-651831D01*
X-14582Y-651516D01*
X-14190Y-650991D01*
X-14034Y-650256D01*
X-14190Y-649521D01*
X-14660Y-648891D01*
X-15365Y-648576D01*
X-16149D01*
X-16619Y-648366D01*
X-17010Y-647841D01*
X-17167Y-647106D01*
X-16932Y-646371D01*
X-16384Y-645846D01*
X-15757Y-645636D01*
X-15130Y-645846D01*
X-14582Y-646371D01*
X-14347Y-647106D01*
X-14504Y-647841D01*
X-14895Y-648366D01*
X-15365Y-648576D01*
X-16149D01*
X-16854Y-648891D01*
X-17324Y-649521D01*
X-17480Y-650256D01*
X-17324Y-650991D01*
X-16932Y-651516D01*
X-16305Y-651831D01*
X-15757Y-651936D01*
G01X-9457D02*
X-8909Y-651831D01*
X-8282Y-651516D01*
X-7890Y-650991D01*
X-7734Y-650256D01*
X-7890Y-649521D01*
X-8360Y-648891D01*
X-9065Y-648576D01*
X-9849D01*
X-10319Y-648366D01*
X-10710Y-647841D01*
X-10867Y-647106D01*
X-10632Y-646371D01*
X-10084Y-645846D01*
X-9457Y-645636D01*
X-8830Y-645846D01*
X-8282Y-646371D01*
X-8047Y-647106D01*
X-8204Y-647841D01*
X-8595Y-648366D01*
X-9065Y-648576D01*
X-9849D01*
X-10554Y-648891D01*
X-11024Y-649521D01*
X-11180Y-650256D01*
X-11024Y-650991D01*
X-10632Y-651516D01*
X-10005Y-651831D01*
X-9457Y-651936D01*
G01X-3314Y-653091D02*
X-3000Y-651726D01*
G01X793Y-645636D02*
X1890Y-651936D01*
X3143Y-645636D01*
X4396Y-651936D01*
X5493Y-645636D01*
G01X11010Y-651936D02*
X7876D01*
Y-645636D01*
X11010D01*
G01X9756Y-648681D02*
X7876D01*
G01X13941Y-651936D02*
Y-645636D01*
X17545Y-651936D01*
Y-645636D01*
G01X26698Y-651936D02*
Y-645636D01*
G01X29988D02*
Y-651936D01*
G01Y-648786D02*
X26698D01*
G01X32293Y-645636D02*
X33390Y-651936D01*
X34643Y-645636D01*
X35896Y-651936D01*
X36993Y-645636D01*
G01X38985Y-651936D02*
X40943Y-645636D01*
X42901Y-651936D01*
G01X42196Y-649731D02*
X39690D01*
G01X52055Y-646686D02*
X52525Y-646056D01*
X53073Y-645741D01*
X53700Y-645636D01*
X54483Y-645846D01*
X55031Y-646371D01*
X55188Y-647001D01*
X55110Y-647631D01*
X54796Y-648156D01*
X53230Y-649206D01*
X52525Y-649941D01*
X52055Y-650991D01*
X51898Y-651936D01*
X55188D01*
G01X58041D02*
Y-645636D01*
X61645Y-651936D01*
Y-645636D01*
G01X64420Y-651936D02*
Y-645636D01*
X65986D01*
X66613Y-645951D01*
X67083Y-646371D01*
X67475Y-647001D01*
X67788Y-647736D01*
X67866Y-648786D01*
X67788Y-649836D01*
X67475Y-650571D01*
X67083Y-651201D01*
X66613Y-651621D01*
X65986Y-651936D01*
X64420D01*
G01X77176D02*
Y-645636D01*
X79135D01*
X79761Y-645951D01*
X80153Y-646371D01*
X80310Y-647211D01*
X80153Y-648051D01*
X79683Y-648576D01*
X79135Y-648891D01*
X77176D01*
G01X79135D02*
X80310Y-651936D01*
G01X83320D02*
Y-645636D01*
X84886D01*
X85513Y-645951D01*
X85983Y-646371D01*
X86375Y-647001D01*
X86688Y-647736D01*
X86766Y-648786D01*
X86688Y-649836D01*
X86375Y-650571D01*
X85983Y-651201D01*
X85513Y-651621D01*
X84886Y-651936D01*
X83320D01*
G01X91343Y-652146D02*
X91186Y-652041D01*
Y-651831D01*
X91343Y-651726D01*
X91500Y-651831D01*
Y-652041D01*
X91343Y-652146D01*
G01X-38207Y407900D02*
Y411000D01*
X-38973D01*
X-39280Y410845D01*
X-39510Y410638D01*
X-39702Y410328D01*
X-39855Y409967D01*
X-39893Y409450D01*
X-39855Y408933D01*
X-39702Y408572D01*
X-39510Y408262D01*
X-39280Y408055D01*
X-38973Y407900D01*
X-38207D01*
G01X-42457Y409553D02*
X-42610Y409708D01*
X-42725Y409967D01*
X-42802Y410328D01*
X-42725Y410638D01*
X-42572Y410845D01*
X-42303Y411000D01*
X-41268D01*
Y407900D01*
X-42533D01*
X-42802Y408107D01*
X-42955Y408417D01*
X-43032Y408778D01*
X-42955Y409140D01*
X-42725Y409450D01*
X-42457Y409553D01*
X-41268D01*
G01X-45250Y407900D02*
Y411000D01*
X-44790Y410380D01*
G01Y407900D02*
X-45710D01*
G01X-44113Y413216D02*
X-17887D01*
X-31000Y447792D01*
X-44113Y413216D01*
G01X-18657Y-639236D02*
X-21177Y-638819D01*
X-23382Y-637153D01*
X-25272Y-634653D01*
X-26532Y-631736D01*
X-27162Y-628403D01*
Y-625069D01*
X-26532Y-621736D01*
X-25272Y-618819D01*
X-23382Y-616320D01*
X-21177Y-614653D01*
X-18657Y-614236D01*
X-16137Y-614653D01*
X-13932Y-616320D01*
X-12042Y-618819D01*
X-10782Y-621736D01*
X-10152Y-625069D01*
Y-628403D01*
X-10782Y-631736D01*
X-12042Y-634653D01*
X-13932Y-637153D01*
X-16137Y-638819D01*
X-18657Y-639236D01*
G01X-16137Y-632569D02*
X-12357Y-639236D01*
G01X1188Y-622570D02*
Y-634236D01*
X2448Y-637153D01*
X4338Y-638819D01*
X6543Y-639236D01*
X8748Y-638819D01*
X10638Y-637153D01*
X11898Y-634236D01*
G01Y-639236D02*
Y-622570D01*
G01X37413Y-639236D02*
Y-622570D01*
G01Y-625486D02*
X36153Y-623820D01*
X34263Y-622986D01*
X32058Y-622570D01*
X29853Y-623403D01*
X27963Y-625069D01*
X26703Y-627570D01*
X26073Y-630903D01*
X26703Y-634236D01*
X27963Y-636737D01*
X29853Y-638403D01*
X32058Y-639236D01*
X34263Y-638819D01*
X36153Y-637570D01*
X37413Y-635903D01*
G01X51588Y-639236D02*
Y-622570D01*
G01Y-626736D02*
X52848Y-624653D01*
X54738Y-622986D01*
X57258Y-622570D01*
X59463Y-622986D01*
X61353Y-624653D01*
X62298Y-627570D01*
Y-639236D01*
G01X82143Y-614236D02*
Y-639236D01*
G01X77733Y-622570D02*
X86553D01*
G01X113013Y-639236D02*
Y-622570D01*
G01Y-625486D02*
X111753Y-623820D01*
X109863Y-622986D01*
X107658Y-622570D01*
X105453Y-623403D01*
X103563Y-625069D01*
X102303Y-627570D01*
X101673Y-630903D01*
X102303Y-634236D01*
X103563Y-636737D01*
X105453Y-638403D01*
X107658Y-639236D01*
X109863Y-638819D01*
X111753Y-637570D01*
X113013Y-635903D01*
G01X2177Y74700D02*
G03X1793Y72974I25124J-6495D01*
G01X21700Y107100D02*
X15500D01*
Y103900D01*
X21700D01*
Y107100D01*
G01X21400Y117800D02*
X15200D01*
Y114600D01*
X21400D01*
Y117800D01*
G01X18400Y107800D02*
Y114000D01*
X15200D01*
Y107800D01*
X18400D01*
G01X16134Y272316D02*
Y266316D01*
G01D02*
X22134D01*
G01Y293875D02*
X16134D01*
G01D02*
Y287875D01*
G01X19119Y337654D02*
X18851Y337706D01*
X18544Y337861D01*
X18352Y338119D01*
X18276Y338481D01*
X18352Y338842D01*
X18582Y339152D01*
X18927Y339307D01*
X19311D01*
X19541Y339411D01*
X19732Y339669D01*
X19809Y340031D01*
X19694Y340392D01*
X19426Y340651D01*
X19119Y340754D01*
X18812Y340651D01*
X18544Y340392D01*
X18429Y340031D01*
X18506Y339669D01*
X18697Y339411D01*
X18927Y339307D01*
X19311D01*
X19656Y339152D01*
X19886Y338842D01*
X19962Y338481D01*
X19886Y338119D01*
X19694Y337861D01*
X19387Y337706D01*
X19119Y337654D01*
G01X18300Y409100D02*
Y412200D01*
X18760Y411580D01*
G01Y409100D02*
X17840D01*
G01X31400Y111200D02*
X33731Y113531D01*
X36840D01*
Y104869D01*
X25960D01*
Y113531D01*
X29069D01*
X31400Y111200D01*
G01X34893Y118000D02*
Y115778D01*
X34740Y115313D01*
X34433Y115003D01*
X34050Y114900D01*
X33667Y115003D01*
X33360Y115313D01*
X33207Y115778D01*
Y118000D01*
G01X31678Y117483D02*
X31448Y117793D01*
X31180Y117948D01*
X30873Y118000D01*
X30490Y117897D01*
X30222Y117638D01*
X30145Y117328D01*
X30183Y117018D01*
X30337Y116760D01*
X31103Y116243D01*
X31448Y115882D01*
X31678Y115365D01*
X31755Y114900D01*
X30145D01*
G01X27390D02*
Y118000D01*
X28808Y115778D01*
X26892D01*
G01X22500Y243500D02*
Y237500D01*
X34500D01*
Y243500D01*
X22500D01*
G01X41431Y285398D02*
X40684Y284773D01*
X39844Y284398D01*
X39098D01*
X38351Y284773D01*
X37791Y285398D01*
X37511Y286273D01*
X37698Y287148D01*
X38164Y287898D01*
X39004Y288398D01*
X40124Y288648D01*
X40778Y289148D01*
X41058Y290023D01*
X40871Y290898D01*
X40404Y291523D01*
X39751Y291898D01*
X39098D01*
X38444Y291648D01*
X37884Y291023D01*
G01X33651Y284148D02*
X30291Y291898D01*
G01X26618Y284398D02*
Y291898D01*
X22324Y284398D01*
Y291898D01*
G01X22600Y317900D02*
Y324100D01*
X19400D01*
Y317900D01*
X22600D01*
G01X40046Y45595D02*
G03X53250Y68200I-12744J22603D01*
G01D02*
G03X40546Y90515I-25951J0D01*
G01X50369Y91515D02*
Y89293D01*
X50216Y88828D01*
X49909Y88518D01*
X49526Y88415D01*
X49143Y88518D01*
X48836Y88828D01*
X48683Y89293D01*
Y91515D01*
G01X46426Y88415D02*
X46158Y88467D01*
X45851Y88622D01*
X45659Y88880D01*
X45583Y89242D01*
X45659Y89603D01*
X45889Y89913D01*
X46234Y90068D01*
X46618D01*
X46848Y90172D01*
X47039Y90430D01*
X47116Y90792D01*
X47001Y91153D01*
X46733Y91412D01*
X46426Y91515D01*
X46119Y91412D01*
X45851Y91153D01*
X45736Y90792D01*
X45813Y90430D01*
X46004Y90172D01*
X46234Y90068D01*
X46618D01*
X46963Y89913D01*
X47193Y89603D01*
X47269Y89242D01*
X47193Y88880D01*
X47001Y88622D01*
X46694Y88467D01*
X46426Y88415D01*
G01X50000Y107800D02*
X43800D01*
Y104600D01*
X50000D01*
Y107800D01*
G01X49600Y92900D02*
Y99100D01*
X46400D01*
Y92900D01*
X49600D01*
G01X43800Y100700D02*
X50000D01*
Y103900D01*
X43800D01*
Y100700D01*
G01X42900Y217100D02*
Y210900D01*
X46100D01*
Y217100D01*
X42900D01*
G01X45430Y218880D02*
X51630D01*
Y222080D01*
X45430D01*
Y218880D01*
G01X43693Y272316D02*
Y266316D01*
G01D02*
X37693D01*
G01Y293875D02*
X43693D01*
G01D02*
Y287875D01*
G01X45400Y342400D02*
X51600D01*
Y345600D01*
X45400D01*
Y342400D01*
G01Y346400D02*
X51600D01*
Y349600D01*
X45400D01*
Y346400D01*
G01Y358400D02*
X51600D01*
Y361600D01*
X45400D01*
Y358400D01*
G01X39380Y375700D02*
Y369500D01*
X42580D01*
Y375700D01*
X39380D01*
G01X51600Y377600D02*
X45400D01*
Y374400D01*
X51600D01*
Y377600D01*
G01X45400Y366400D02*
X51600D01*
Y369600D01*
X45400D01*
Y366400D01*
G01Y370400D02*
X51600D01*
Y373600D01*
X45400D01*
Y370400D01*
G01X51600Y385600D02*
X45400D01*
Y382400D01*
X51600D01*
Y385600D01*
G01Y389600D02*
X45400D01*
Y386400D01*
X51600D01*
Y389600D01*
G01Y381600D02*
X45400D01*
Y378400D01*
X51600D01*
Y381600D01*
G01X53000Y393787D02*
Y396213D01*
G01X46531Y402205D02*
X50469D01*
X48500Y400237D01*
X46531Y402205D01*
G01Y399843D02*
X50469D01*
G01X45850Y392874D02*
X45750D01*
Y392224D01*
X51250D01*
Y392924D01*
X51000D01*
Y392524D01*
X45750D01*
Y391774D01*
X51250D01*
Y392274D01*
G01X45744Y409074D02*
Y392926D01*
X51256D01*
Y409074D01*
X45744D01*
G01X46900Y422100D02*
Y415900D01*
X50100D01*
Y422100D01*
X46900D01*
G01X42000Y415700D02*
Y421900D01*
X38800D01*
Y415700D01*
X42000D01*
G01X46000D02*
Y421900D01*
X42800D01*
Y415700D01*
X46000D01*
G01X50727Y412000D02*
X48487D01*
G01X49700Y413625D02*
Y410375D01*
G01X61259Y40644D02*
Y43744D01*
X61719Y43124D01*
G01Y40644D02*
X60799D01*
G01X61787Y53527D02*
X61557Y53837D01*
X61289Y53992D01*
X60982Y54044D01*
X60599Y53941D01*
X60331Y53682D01*
X60254Y53372D01*
X60292Y53062D01*
X60446Y52804D01*
X61212Y52287D01*
X61557Y51926D01*
X61787Y51409D01*
X61864Y50944D01*
X60254D01*
G01X57100Y77400D02*
Y83600D01*
X53900D01*
Y77400D01*
X57100D01*
G01Y68400D02*
Y74600D01*
X53900D01*
Y68400D01*
X57100D01*
G01X66100Y67400D02*
Y73600D01*
X62900D01*
Y67400D01*
X66100D01*
G01X61100Y68400D02*
Y74600D01*
X57900D01*
Y68400D01*
X61100D01*
G01X57900Y83600D02*
Y77400D01*
X61100D01*
Y83600D01*
X57900D01*
G01X53900Y84400D02*
X60100D01*
Y87600D01*
X53900D01*
Y84400D01*
G01X60331Y100512D02*
Y89488D01*
G01Y100512D02*
X51669D01*
Y89488D01*
X60331D01*
G01X61600Y101900D02*
Y108100D01*
X58400D01*
Y101900D01*
X61600D01*
G01X62816Y228200D02*
Y234400D01*
X59616D01*
Y228200D01*
X62816D01*
G01X71504Y261700D02*
X59496D01*
Y251300D01*
X71504D01*
Y254500D01*
X69437Y256500D01*
X71504Y258500D01*
Y261700D01*
G01X54500Y332600D02*
Y326400D01*
X57700D01*
Y332600D01*
X54500D01*
G01X65700Y326400D02*
Y332600D01*
X62500D01*
Y326400D01*
X65700D01*
G01X58400Y332600D02*
Y326400D01*
X61600D01*
Y332600D01*
X58400D01*
G01X50600D02*
Y326400D01*
X53800D01*
Y332600D01*
X50600D01*
G01X60439Y345477D02*
X64823Y349861D01*
X62561Y352123D01*
X58177Y347739D01*
X60439Y345477D01*
G01X48400Y357600D02*
Y351400D01*
X51600D01*
Y357600D01*
X48400D01*
G01X55100Y374700D02*
X61300D01*
Y377900D01*
X55100D01*
Y374700D01*
G01X55400Y366100D02*
X61600D01*
Y369300D01*
X55400D01*
Y366100D01*
G01X55100Y371000D02*
X61300D01*
Y374200D01*
X55100D01*
Y371000D01*
G01X55663Y391589D02*
X60047Y387205D01*
X62309Y389467D01*
X57925Y393851D01*
X55663Y391589D01*
G01X56767Y398480D02*
X63980Y391267D01*
X67233Y394520D01*
X60020Y401733D01*
X56767Y398480D01*
G01X60374Y394874D02*
X63626Y398126D01*
G01X52500Y401007D02*
X55600D01*
Y401773D01*
X55445Y402080D01*
X55238Y402310D01*
X54928Y402502D01*
X54567Y402655D01*
X54050Y402693D01*
X53533Y402655D01*
X53172Y402502D01*
X52862Y402310D01*
X52655Y402080D01*
X52500Y401773D01*
Y401007D01*
G01X55083Y404222D02*
X55393Y404452D01*
X55548Y404720D01*
X55600Y405027D01*
X55497Y405410D01*
X55238Y405678D01*
X54928Y405755D01*
X54618Y405717D01*
X54360Y405563D01*
X53843Y404797D01*
X53482Y404452D01*
X52965Y404222D01*
X52500Y404145D01*
Y405755D01*
G01X53120Y407207D02*
X52758Y407437D01*
X52552Y407743D01*
X52500Y408088D01*
X52552Y408395D01*
X52810Y408702D01*
X53120Y408893D01*
X53430Y408932D01*
X53792Y408855D01*
X54050Y408587D01*
X54153Y408318D01*
Y407973D01*
G01Y408318D02*
X54308Y408548D01*
X54567Y408740D01*
X54877Y408817D01*
X55187Y408740D01*
X55445Y408548D01*
X55600Y408203D01*
X55548Y407858D01*
X55342Y407513D01*
G01X54900Y422100D02*
Y415900D01*
X58100D01*
Y422100D01*
X54900D01*
G01X50900D02*
Y415900D01*
X54100D01*
Y422100D01*
X50900D01*
G01X58900D02*
Y415900D01*
X62100D01*
Y422100D01*
X58900D01*
G01X56370Y431500D02*
X55603D01*
Y430570D01*
X55833Y430260D01*
X56102Y430053D01*
X56485Y429950D01*
X56868Y430053D01*
X57137Y430260D01*
X57367Y430570D01*
X57520Y430932D01*
X57597Y431345D01*
Y431707D01*
X57520Y432017D01*
X57367Y432378D01*
X57137Y432688D01*
X56907Y432895D01*
X56600Y433050D01*
X56332D01*
X56025Y432947D01*
X55795Y432740D01*
G01X54228Y429950D02*
Y433050D01*
X52772D01*
G01X53308Y431552D02*
X54228D01*
G01X50400Y429950D02*
Y433050D01*
X50860Y432430D01*
G01Y429950D02*
X49940D01*
G01X52224Y434645D02*
X60800D01*
G01X52431Y439048D02*
X53389Y435948D01*
X54347Y439048D01*
G01X54002Y437963D02*
X52776D01*
G01X56412Y439048D02*
X56489Y438376D01*
X56604Y437808D01*
X56757Y437291D01*
X56949Y436723D01*
X57256Y435948D01*
X55722D01*
G01X59589D02*
X59282Y436051D01*
X59052Y436310D01*
X58899Y436620D01*
X58784Y437033D01*
X58746Y437498D01*
X58784Y437963D01*
X58899Y438376D01*
X59052Y438686D01*
X59282Y438945D01*
X59589Y439048D01*
X59896Y438945D01*
X60126Y438686D01*
X60279Y438376D01*
X60394Y437963D01*
X60432Y437498D01*
X60394Y437033D01*
X60279Y436620D01*
X60126Y436310D01*
X59896Y436051D01*
X59589Y435948D01*
G01X52224Y450393D02*
Y471063D01*
X55177Y474015D01*
X121555D01*
X124508Y471063D01*
Y451870D01*
G03X129921Y446456I5413J-1D01*
G03X135335Y451870I0J5414D01*
G01Y471063D01*
X138287Y474015D01*
X171595D01*
X174547Y471063D01*
Y450098D01*
G03X178189Y446456I3642J0D01*
G03X181831Y450098I0J3642D01*
G01Y471063D01*
X184783Y474015D01*
X251122D01*
X254075Y471063D01*
Y450885D01*
G03X258504Y446456I4429J0D01*
G03X262933Y450885I0J4429D01*
G01Y471063D01*
X265886Y474015D01*
X299173D01*
X302126Y471063D01*
Y450393D01*
G01X70900Y73600D02*
Y67400D01*
X74100D01*
Y73600D01*
X70900D01*
G01X70100Y67400D02*
Y73600D01*
X66900D01*
Y67400D01*
X70100D01*
G01X76400Y74400D02*
X82600D01*
Y77600D01*
X76400D01*
Y74400D01*
G01X73600Y78100D02*
X67400D01*
Y74900D01*
X73600D01*
Y78100D01*
G01X74900Y73600D02*
Y67400D01*
X78100D01*
Y73600D01*
X74900D01*
G01X82300Y101000D02*
X75700D01*
Y88000D01*
X82300D01*
Y101000D01*
G01X73800D02*
X67200D01*
Y88000D01*
X73800D01*
Y101000D01*
G01X75700Y94500D02*
X82300D01*
G01X67200D02*
X73800D01*
G01X66816Y228200D02*
Y234400D01*
X63616D01*
Y228200D01*
X66816D01*
G01X67900Y240600D02*
Y234400D01*
X71100D01*
Y240600D01*
X67900D01*
G01X75600Y251307D02*
X73378D01*
X72913Y251460D01*
X72603Y251767D01*
X72500Y252150D01*
X72603Y252533D01*
X72913Y252840D01*
X73378Y252993D01*
X75600D01*
G01X73120Y254407D02*
X72758Y254637D01*
X72552Y254943D01*
X72500Y255288D01*
X72552Y255595D01*
X72810Y255902D01*
X73120Y256093D01*
X73430Y256132D01*
X73792Y256055D01*
X74050Y255787D01*
X74153Y255518D01*
Y255173D01*
G01Y255518D02*
X74308Y255748D01*
X74567Y255940D01*
X74877Y256017D01*
X75187Y255940D01*
X75445Y255748D01*
X75600Y255403D01*
X75548Y255058D01*
X75342Y254713D01*
G01X72500Y258273D02*
X73172Y258350D01*
X73740Y258465D01*
X74257Y258618D01*
X74825Y258810D01*
X75600Y259117D01*
Y257583D01*
G01X64400Y279100D02*
Y272900D01*
X67600D01*
Y279100D01*
X64400D01*
G01X68400D02*
Y272900D01*
X71600D01*
Y279100D01*
X68400D01*
G01X67600Y283400D02*
Y289600D01*
X64400D01*
Y283400D01*
X67600D01*
G01X68600Y285500D02*
X74800D01*
Y288700D01*
X68600D01*
Y285500D01*
G01X75900Y273000D02*
Y279200D01*
X72700D01*
Y273000D01*
X75900D01*
G01X93507Y293342D02*
X93737Y293497D01*
X94005Y293600D01*
X94312D01*
X94657Y293445D01*
X94925Y293187D01*
X95117Y292877D01*
X95270Y292360D01*
X95308Y291895D01*
X95232Y291430D01*
X95117Y291120D01*
X94887Y290810D01*
X94618Y290603D01*
X94350Y290500D01*
X94082D01*
X93813Y290603D01*
X93583Y290758D01*
X93392Y290965D01*
G01X92017Y290500D02*
Y293600D01*
X91097D01*
X90790Y293445D01*
X90560Y293083D01*
X90483Y292670D01*
X90560Y292257D01*
X90752Y291947D01*
X91097Y291792D01*
X92017D01*
G01X88917Y293600D02*
Y290500D01*
X87383D01*
G01X85893D02*
Y293600D01*
X85127D01*
X84820Y293445D01*
X84590Y293238D01*
X84398Y292928D01*
X84245Y292567D01*
X84207Y292050D01*
X84245Y291533D01*
X84398Y291172D01*
X84590Y290862D01*
X84820Y290655D01*
X85127Y290500D01*
X85893D01*
G01X83100Y289467D02*
X80800D01*
G01X79578Y293083D02*
X79348Y293393D01*
X79080Y293548D01*
X78773Y293600D01*
X78390Y293497D01*
X78122Y293238D01*
X78045Y292928D01*
X78083Y292618D01*
X78237Y292360D01*
X79003Y291843D01*
X79348Y291482D01*
X79578Y290965D01*
X79655Y290500D01*
X78045D01*
G01X76593Y290965D02*
X76363Y290707D01*
X76095Y290552D01*
X75750Y290500D01*
X75405Y290603D01*
X75137Y290810D01*
X74945Y291172D01*
X74907Y291585D01*
X74983Y291998D01*
X75175Y292257D01*
X75443Y292463D01*
X75712Y292515D01*
X75980Y292463D01*
X76325Y292257D01*
X76210Y293600D01*
X75175D01*
G01X73647Y290500D02*
Y293600D01*
X72650Y291017D01*
X71653Y293600D01*
Y290500D01*
G01X70355D02*
Y293600D01*
G01X68745D02*
Y290500D01*
G01Y292050D02*
X70355D01*
G01X67025Y292567D02*
X65875D01*
X67025Y290500D01*
X65875D01*
G01X74961Y310645D02*
X88829D01*
Y299645D01*
X74961D01*
Y310645D01*
G01X74200Y295100D02*
X80400D01*
Y298300D01*
X74200D01*
Y295100D01*
G01X73500Y305400D02*
Y311600D01*
X70300D01*
Y305400D01*
X73500D01*
G01X66400Y321100D02*
Y314900D01*
X69600D01*
Y321100D01*
X66400D01*
G01X70400Y332600D02*
Y326400D01*
X73600D01*
Y332600D01*
X70400D01*
G01X66500D02*
Y326400D01*
X69700D01*
Y332600D01*
X66500D01*
G01X78100Y326400D02*
Y332600D01*
X74900D01*
Y326400D01*
X78100D01*
G01X70740Y336820D02*
X64540D01*
Y333620D01*
X70740D01*
Y336820D01*
G01X69163Y355430D02*
Y353130D01*
X74613D01*
Y355430D01*
X69163D01*
G01Y358579D02*
Y356279D01*
X74613D01*
Y358579D01*
X69163D01*
G01X69162Y352280D02*
Y349980D01*
X74612D01*
Y352280D01*
X69162D01*
G01X75514Y375275D02*
X77814D01*
Y380725D01*
X75514D01*
Y375275D01*
G01X75439Y371150D02*
Y368850D01*
X80889D01*
Y371150D01*
X75439D01*
G01X75462Y362579D02*
X77762D01*
Y368029D01*
X75462D01*
Y362579D01*
G01X69162Y374327D02*
Y372027D01*
X74612D01*
Y374327D01*
X69162D01*
G01Y377477D02*
Y375177D01*
X74612D01*
Y377477D01*
X69162D01*
G01X73400Y391600D02*
Y385400D01*
X76600D01*
Y391600D01*
X73400D01*
G01X67400D02*
Y385400D01*
X70600D01*
Y391600D01*
X67400D01*
G01X69182Y378307D02*
X71482D01*
Y383757D01*
X69182D01*
Y378307D01*
G01X74632Y383776D02*
X72332D01*
Y378326D01*
X74632D01*
Y383776D01*
G01X80100Y398400D02*
Y404600D01*
X76900D01*
Y398400D01*
X80100D01*
G01X76100D02*
Y404600D01*
X72900D01*
Y398400D01*
X76100D01*
G01X72100D02*
Y404600D01*
X68900D01*
Y398400D01*
X72100D01*
G01X64100Y434645D02*
X92400D01*
G01X84900Y73600D02*
Y67400D01*
X88100D01*
Y73600D01*
X84900D01*
G01X84100Y67400D02*
Y73600D01*
X80900D01*
Y67400D01*
X84100D01*
G01X92100Y70400D02*
Y76600D01*
X88900D01*
Y70400D01*
X92100D01*
G01X89800Y101000D02*
X83200D01*
Y88000D01*
X89800D01*
Y101000D01*
G01X99000D02*
X92400D01*
Y88000D01*
X99000D01*
Y101000D01*
G01X83200Y94500D02*
X89800D01*
G01X92400D02*
X99000D01*
G01X79000Y259500D02*
Y253300D01*
X82200D01*
Y259500D01*
X79000D01*
G01X90800Y295850D02*
X91013Y295892D01*
X91200Y296058D01*
X91360Y296308D01*
X91467Y296600D01*
X91520Y296933D01*
Y297267D01*
X91467Y297600D01*
X91360Y297892D01*
X91200Y298142D01*
X91013Y298308D01*
X90800Y298350D01*
X90587Y298308D01*
X90400Y298142D01*
X90240Y297892D01*
X90133Y297600D01*
X90080Y297267D01*
Y296933D01*
X90133Y296600D01*
X90240Y296308D01*
X90400Y296058D01*
X90587Y295892D01*
X90800Y295850D01*
G01X89160Y296183D02*
X88947Y295975D01*
X88707Y295850D01*
X88493D01*
X88280Y295975D01*
X88120Y296183D01*
X88040Y296475D01*
X88093Y296767D01*
X88227Y297017D01*
X88467Y297183D01*
X88787Y297267D01*
X88973Y297433D01*
X89053Y297725D01*
X89000Y298017D01*
X88867Y298225D01*
X88680Y298350D01*
X88493D01*
X88307Y298267D01*
X88147Y298058D01*
G01X85813Y298142D02*
X85973Y298267D01*
X86160Y298350D01*
X86373D01*
X86613Y298225D01*
X86800Y298017D01*
X86933Y297767D01*
X87040Y297350D01*
X87067Y296975D01*
X87013Y296600D01*
X86933Y296350D01*
X86773Y296100D01*
X86587Y295933D01*
X86400Y295850D01*
X86213D01*
X86027Y295933D01*
X85867Y296058D01*
X85733Y296225D01*
G01X84707Y297933D02*
X84547Y298183D01*
X84360Y298308D01*
X84147Y298350D01*
X83880Y298267D01*
X83693Y298058D01*
X83640Y297808D01*
X83667Y297558D01*
X83773Y297350D01*
X84307Y296933D01*
X84547Y296642D01*
X84707Y296225D01*
X84760Y295850D01*
X83640D01*
G01X90300Y326400D02*
Y332600D01*
X87100D01*
Y326400D01*
X90300D01*
G01X90360Y361729D02*
X88060D01*
Y356279D01*
X90360D01*
Y361729D01*
G01X85050Y360425D02*
X82750D01*
Y354975D01*
X85050D01*
Y360425D01*
G01X92561Y375678D02*
Y373378D01*
X98011D01*
Y375678D01*
X92561D01*
G01X84061Y377477D02*
X81761D01*
Y372027D01*
X84061D01*
Y377477D01*
G01X82714Y361175D02*
X85014D01*
Y366625D01*
X82714D01*
Y361175D01*
G01X78702Y362675D02*
X81002D01*
Y368125D01*
X78702D01*
Y362675D01*
G01X87211Y377477D02*
X84911D01*
Y372027D01*
X87211D01*
Y377477D01*
G01X91911Y367378D02*
Y369678D01*
X86461D01*
Y367378D01*
X91911D01*
G01X90360Y377477D02*
X88060D01*
Y372027D01*
X90360D01*
Y377477D01*
G01X96660Y381476D02*
Y383776D01*
X91210D01*
Y381476D01*
X96660D01*
G01X84100Y398400D02*
Y404600D01*
X80900D01*
Y398400D01*
X84100D01*
G01X84900Y404600D02*
Y398400D01*
X88100D01*
Y404600D01*
X84900D01*
G01X94409Y416230D02*
Y422430D01*
X91209D01*
Y416230D01*
X94409D01*
G01X90400Y416200D02*
Y422400D01*
X87200D01*
Y416200D01*
X90400D01*
G01X100136Y40794D02*
X100059Y41466D01*
X99944Y42034D01*
X99791Y42551D01*
X99599Y43119D01*
X99292Y43894D01*
X100826D01*
G01X100259Y50944D02*
X99991Y50996D01*
X99684Y51151D01*
X99492Y51409D01*
X99416Y51771D01*
X99492Y52132D01*
X99722Y52442D01*
X100067Y52597D01*
X100451D01*
X100681Y52701D01*
X100872Y52959D01*
X100949Y53321D01*
X100834Y53682D01*
X100566Y53941D01*
X100259Y54044D01*
X99952Y53941D01*
X99684Y53682D01*
X99569Y53321D01*
X99646Y52959D01*
X99837Y52701D01*
X100067Y52597D01*
X100451D01*
X100796Y52442D01*
X101026Y52132D01*
X101102Y51771D01*
X101026Y51409D01*
X100834Y51151D01*
X100527Y50996D01*
X100259Y50944D01*
G01X101361Y76966D02*
X107561D01*
Y80166D01*
X101361D01*
Y76966D01*
G01X92900Y74100D02*
Y67900D01*
X96100D01*
Y74100D01*
X92900D01*
G01X100100Y67900D02*
Y74100D01*
X96900D01*
Y67900D01*
X100100D01*
G01X105100Y133307D02*
X108200D01*
Y134073D01*
X108045Y134380D01*
X107838Y134610D01*
X107528Y134802D01*
X107167Y134955D01*
X106650Y134993D01*
X106133Y134955D01*
X105772Y134802D01*
X105462Y134610D01*
X105255Y134380D01*
X105100Y134073D01*
Y133307D01*
G01Y137250D02*
X108200D01*
X107580Y136790D01*
G01X105100D02*
Y137710D01*
G01Y140350D02*
X108200D01*
X107580Y139890D01*
G01X105100D02*
Y140810D01*
G01X100900Y133307D02*
X104000D01*
Y134073D01*
X103845Y134380D01*
X103638Y134610D01*
X103328Y134802D01*
X102967Y134955D01*
X102450Y134993D01*
X101933Y134955D01*
X101572Y134802D01*
X101262Y134610D01*
X101055Y134380D01*
X100900Y134073D01*
Y133307D01*
G01X101262Y136598D02*
X101003Y136867D01*
X100900Y137173D01*
X101003Y137480D01*
X101313Y137748D01*
X101778Y137940D01*
X102243Y138017D01*
X102812D01*
X103277Y137940D01*
X103690Y137748D01*
X103897Y137518D01*
X104000Y137250D01*
X103897Y136943D01*
X103690Y136713D01*
X103380Y136560D01*
X102967Y136483D01*
X102605Y136560D01*
X102243Y136752D01*
X102037Y136982D01*
X101985Y137250D01*
X102088Y137557D01*
X102347Y137787D01*
X102812Y138017D01*
G01X111327Y159657D02*
X109087D01*
G01X110300Y161282D02*
Y158032D01*
G01X98171Y229710D02*
Y232810D01*
G01X96561D02*
Y229710D01*
G01Y231260D02*
X98171D01*
G01X94266Y229710D02*
Y232810D01*
X94726Y232190D01*
G01Y229710D02*
X93806D01*
G01X107200Y329100D02*
Y335300D01*
X104000D01*
Y329100D01*
X107200D01*
G01X110625Y343249D02*
X104425D01*
Y340049D01*
X110625D01*
Y343249D01*
G01X110700Y339300D02*
X104500D01*
Y336100D01*
X110700D01*
Y339300D01*
G01X102400Y365600D02*
Y359400D01*
X105600D01*
Y365600D01*
X102400D01*
G01X101600Y361600D02*
X95400D01*
Y358400D01*
X101600D01*
Y361600D01*
G01X103808Y346831D02*
X106108D01*
Y352281D01*
X103808D01*
Y346831D01*
G01X97509Y352280D02*
Y349980D01*
X102959D01*
Y352280D01*
X97509D01*
G01X100659Y355430D02*
Y353130D01*
X106109D01*
Y355430D01*
X100659D01*
G01X102275Y358650D02*
Y356350D01*
X107725D01*
Y358650D01*
X102275D01*
G01X101600Y365600D02*
X95400D01*
Y362400D01*
X101600D01*
Y365600D01*
G01X102800Y370200D02*
Y376400D01*
X99600D01*
Y370200D01*
X102800D01*
G01X93275Y368650D02*
Y366350D01*
X98725D01*
Y368650D01*
X93275D01*
G01Y372150D02*
Y369850D01*
X98725D01*
Y372150D01*
X93275D01*
G01X105400Y379900D02*
Y386100D01*
X102200D01*
Y379900D01*
X105400D01*
G01X110047Y394851D02*
X105663Y390467D01*
X107925Y388205D01*
X112309Y392589D01*
X110047Y394851D01*
G01X105561Y395823D02*
X101177Y391439D01*
X103439Y389177D01*
X107823Y393561D01*
X105561Y395823D01*
G01X101689Y377150D02*
Y379450D01*
X96239D01*
Y377150D01*
X101689D01*
G01X97514Y381475D02*
X99814D01*
Y386925D01*
X97514D01*
Y381475D01*
G01X109800Y402000D02*
X105200D01*
G01X109800Y396500D02*
X105200D01*
G01X105300Y406500D02*
X105200D01*
Y396500D01*
G01X109800Y401000D02*
X105200D01*
G01X96100Y398400D02*
Y404600D01*
X92900D01*
Y398400D01*
X96100D01*
G01X104100D02*
Y404600D01*
X100900D01*
Y398400D01*
X104100D01*
G01X96900Y404600D02*
Y398400D01*
X100100D01*
Y404600D01*
X96900D01*
G01X109800Y406500D02*
X105200D01*
G01X98414Y416230D02*
Y422430D01*
X95214D01*
Y416230D01*
X98414D01*
G01X97400Y434645D02*
X126649D01*
G01X115000Y61807D02*
X118100D01*
Y62573D01*
X117945Y62880D01*
X117738Y63110D01*
X117428Y63302D01*
X117067Y63455D01*
X116550Y63493D01*
X116033Y63455D01*
X115672Y63302D01*
X115362Y63110D01*
X115155Y62880D01*
X115000Y62573D01*
Y61807D01*
G01Y65750D02*
X118100D01*
X117480Y65290D01*
G01X115000D02*
Y66210D01*
G01X116292Y68122D02*
X116653Y68390D01*
X116860Y68620D01*
X116963Y68927D01*
X116860Y69195D01*
X116653Y69387D01*
X116343Y69540D01*
X115982Y69578D01*
X115672Y69540D01*
X115362Y69387D01*
X115103Y69157D01*
X115000Y68888D01*
X115103Y68582D01*
X115413Y68313D01*
X115878Y68160D01*
X116395Y68122D01*
X117067Y68198D01*
X117428Y68313D01*
X117790Y68505D01*
X118048Y68773D01*
X118100Y69042D01*
X117997Y69310D01*
X117738Y69502D01*
G01X119500Y61922D02*
X122600D01*
Y63378D01*
G01X121102Y62842D02*
Y61922D01*
G01X119913Y64945D02*
X119655Y65252D01*
X119500Y65597D01*
Y65903D01*
X119655Y66210D01*
X119913Y66440D01*
X120275Y66555D01*
X120637Y66478D01*
X120947Y66287D01*
X121153Y65942D01*
X121257Y65482D01*
X121463Y65213D01*
X121825Y65098D01*
X122187Y65175D01*
X122445Y65367D01*
X122600Y65635D01*
Y65903D01*
X122497Y66172D01*
X122238Y66402D01*
G01X119500Y68850D02*
X122600D01*
X121980Y68390D01*
G01X119500D02*
Y69310D01*
G01X116500Y73773D02*
Y76013D01*
G01X118125Y74800D02*
X114875D01*
G01X119000Y86500D02*
X114000D01*
Y77139D01*
X119000D01*
Y86500D01*
X114000D01*
G01X120769Y89069D02*
Y72531D01*
X129431D01*
Y89069D01*
X120769D01*
G01X116700Y88287D02*
Y90713D01*
G01X119000Y86300D02*
X114000D01*
G01X119000Y85900D02*
X114000D01*
G01X119000Y85500D02*
X114000D01*
G01X118000Y110900D02*
X111800D01*
Y107700D01*
X118000D01*
Y110900D01*
G01X117200Y116425D02*
Y122625D01*
X114000D01*
Y116425D01*
X117200D01*
G01X113200D02*
Y122625D01*
X110000D01*
Y116425D01*
X113200D01*
G01X110900Y130600D02*
Y124400D01*
X114100D01*
Y130600D01*
X110900D01*
G01X121900Y129600D02*
Y123400D01*
X125100D01*
Y129600D01*
X121900D01*
G01X122230Y133884D02*
Y136310D01*
G01X113074Y134041D02*
Y136467D01*
G01X122156Y151050D02*
Y149050D01*
G01Y146550D02*
Y144550D01*
G01X120156Y146550D02*
X124156D01*
G01X120156Y149050D02*
X124156D01*
X122156Y146550D01*
X120156Y149050D01*
G01X118613Y156707D02*
X125699D01*
Y137693D01*
X118613D01*
Y156707D01*
G01X113000Y151207D02*
Y149207D01*
G01Y146707D02*
Y144707D01*
G01X111000Y146707D02*
X115000D01*
G01X111000Y149207D02*
X115000D01*
X113000Y146707D01*
X111000Y149207D01*
G01X109457Y156864D02*
X116543D01*
Y137850D01*
X109457D01*
Y156864D01*
G01X121850Y159950D02*
Y166150D01*
X118650D01*
Y159950D01*
X121850D01*
G01X118847Y157204D02*
Y159444D01*
G01X120472Y158231D02*
X117222D01*
G01X110800Y248300D02*
X117000D01*
Y251500D01*
X110800D01*
Y248300D01*
G01X116700Y258807D02*
X114478D01*
X114013Y258960D01*
X113703Y259267D01*
X113600Y259650D01*
X113703Y260033D01*
X114013Y260340D01*
X114478Y260493D01*
X116700D01*
G01X113600Y262673D02*
X114272Y262750D01*
X114840Y262865D01*
X115357Y263018D01*
X115925Y263210D01*
X116700Y263517D01*
Y261983D01*
G01X117600Y272300D02*
Y258700D01*
G01D02*
X126400D01*
G01X120900Y275400D02*
X127100D01*
Y278600D01*
X120900D01*
Y275400D01*
G01X126400Y272300D02*
X117600D01*
G01X112900Y356900D02*
X119100D01*
Y360100D01*
X112900D01*
Y356900D01*
G01X117770Y353380D02*
Y347180D01*
X120970D01*
Y353380D01*
X117770D01*
G01X119119Y364223D02*
X112919D01*
Y361023D01*
X119119D01*
Y364223D01*
G01X119200Y368200D02*
X113000D01*
Y365000D01*
X119200D01*
Y368200D01*
G01X122700Y378400D02*
X116500D01*
Y375200D01*
X122700D01*
Y378400D01*
G01X112900Y399700D02*
X123100D01*
Y404300D01*
X112900D01*
Y399700D01*
G01X118000D02*
Y404300D01*
G01X109800Y396500D02*
Y406500D01*
G01X114900Y395400D02*
X121100D01*
Y398600D01*
X114900D01*
Y395400D01*
G01X119000Y415200D02*
Y421400D01*
X115800D01*
Y415200D01*
X119000D01*
G01X114231Y439548D02*
X115189Y436448D01*
X116147Y439548D01*
G01X115802Y438463D02*
X114576D01*
G01X118749Y439548D02*
Y436448D01*
X117331Y438670D01*
X119247D01*
G01X120546Y438928D02*
X120776Y439290D01*
X121082Y439496D01*
X121427Y439548D01*
X121734Y439496D01*
X122041Y439238D01*
X122232Y438928D01*
X122271Y438618D01*
X122194Y438256D01*
X121926Y437998D01*
X121657Y437895D01*
X121312D01*
G01X121657D02*
X121887Y437740D01*
X122079Y437481D01*
X122156Y437171D01*
X122079Y436861D01*
X121887Y436603D01*
X121542Y436448D01*
X121197Y436500D01*
X120852Y436706D01*
G01X144693Y14267D02*
Y12045D01*
X144540Y11580D01*
X144233Y11270D01*
X143850Y11167D01*
X143467Y11270D01*
X143160Y11580D01*
X143007Y12045D01*
Y14267D01*
G01X141593Y11787D02*
X141363Y11425D01*
X141057Y11219D01*
X140712Y11167D01*
X140405Y11219D01*
X140098Y11477D01*
X139907Y11787D01*
X139868Y12097D01*
X139945Y12459D01*
X140213Y12717D01*
X140482Y12820D01*
X140827D01*
G01X140482D02*
X140252Y12975D01*
X140060Y13234D01*
X139983Y13544D01*
X140060Y13854D01*
X140252Y14112D01*
X140597Y14267D01*
X140942Y14215D01*
X141287Y14009D01*
G01X138493Y11787D02*
X138263Y11425D01*
X137957Y11219D01*
X137612Y11167D01*
X137305Y11219D01*
X136998Y11477D01*
X136807Y11787D01*
X136768Y12097D01*
X136845Y12459D01*
X137113Y12717D01*
X137382Y12820D01*
X137727D01*
G01X137382D02*
X137152Y12975D01*
X136960Y13234D01*
X136883Y13544D01*
X136960Y13854D01*
X137152Y14112D01*
X137497Y14267D01*
X137842Y14215D01*
X138187Y14009D01*
G01X137000Y85900D02*
X130800D01*
Y82700D01*
X137000D01*
Y85900D01*
G01X134000Y86800D02*
Y93000D01*
X130800D01*
Y86800D01*
X134000D01*
G01X135200Y121000D02*
X139800D01*
G01X135200Y131000D02*
Y121000D01*
G01X131099Y114900D02*
Y121100D01*
X127901D01*
Y114900D01*
X131099D01*
G01X127100Y116400D02*
Y122600D01*
X123900D01*
Y116400D01*
X127100D01*
G01X127628Y147132D02*
Y136932D01*
X132228D01*
Y147132D01*
X127628D01*
G01X135200Y125500D02*
X139800D01*
G01X135200Y131000D02*
X139800D01*
G01X135200Y126500D02*
X139800D01*
G01X127628Y142032D02*
X132228D01*
G01X133900Y145600D02*
Y139400D01*
X137100D01*
Y145600D01*
X133900D01*
G01X127495Y158150D02*
Y147950D01*
X132095D01*
Y158150D01*
X127495D01*
G01X126100Y159950D02*
Y166150D01*
X122900D01*
Y159950D01*
X126100D01*
G01X138700Y197200D02*
X132500D01*
Y194000D01*
X138700D01*
Y197200D01*
G01X129146Y226622D02*
Y232822D01*
X125946D01*
Y226622D01*
X129146D01*
G01X128900Y236400D02*
X122700D01*
Y233200D01*
X128900D01*
Y236400D01*
G01Y239900D02*
X122700D01*
Y236700D01*
X128900D01*
Y239900D01*
G01X124700Y248100D02*
X130900D01*
Y251300D01*
X124700D01*
Y248100D01*
G01X140300Y252300D02*
X134100D01*
Y249100D01*
X140300D01*
Y252300D01*
G01X126400Y264500D02*
Y258700D01*
G01Y272300D02*
Y266500D01*
G01D02*
X124900Y265500D01*
X126400Y264500D01*
G01X130100Y272300D02*
Y258700D01*
G01D02*
X138900D01*
G01Y266500D02*
X137400Y265500D01*
X138900Y264500D01*
G01X125500Y281400D02*
X131700D01*
Y284600D01*
X125500D01*
Y281400D01*
G01X135600Y278600D02*
X129400D01*
Y275400D01*
X135600D01*
Y278600D01*
G01X138900Y272300D02*
X130100D01*
G01X132100Y363100D02*
X125900D01*
Y359900D01*
X132100D01*
Y363100D01*
G01X125900Y355900D02*
X132100D01*
Y359100D01*
X125900D01*
Y355900D01*
G01Y351900D02*
X132100D01*
Y355100D01*
X125900D01*
Y351900D01*
G01X124149Y389524D02*
Y384300D01*
X126350Y382300D01*
X124149Y380300D01*
Y375076D01*
X136551D01*
Y389524D01*
X124149D01*
G01X140600Y379057D02*
X138378D01*
X137913Y379210D01*
X137603Y379517D01*
X137500Y379900D01*
X137603Y380283D01*
X137913Y380590D01*
X138378Y380743D01*
X140600D01*
G01X137965Y382157D02*
X137707Y382387D01*
X137552Y382655D01*
X137500Y383000D01*
X137603Y383345D01*
X137810Y383613D01*
X138172Y383805D01*
X138585Y383843D01*
X138998Y383767D01*
X139257Y383575D01*
X139463Y383307D01*
X139515Y383038D01*
X139463Y382770D01*
X139257Y382425D01*
X140600Y382540D01*
Y383575D01*
G01X137500Y386100D02*
X137552Y386368D01*
X137707Y386675D01*
X137965Y386867D01*
X138327Y386943D01*
X138688Y386867D01*
X138998Y386637D01*
X139153Y386292D01*
Y385908D01*
X139257Y385678D01*
X139515Y385487D01*
X139877Y385410D01*
X140238Y385525D01*
X140497Y385793D01*
X140600Y386100D01*
X140497Y386407D01*
X140238Y386675D01*
X139877Y386790D01*
X139515Y386713D01*
X139257Y386522D01*
X139153Y386292D01*
Y385908D01*
X138998Y385563D01*
X138688Y385333D01*
X138327Y385257D01*
X137965Y385333D01*
X137707Y385525D01*
X137552Y385832D01*
X137500Y386100D01*
G01X131600Y397900D02*
Y404100D01*
X128400D01*
Y397900D01*
X131600D01*
G01X124400Y404100D02*
Y397900D01*
X127600D01*
Y404100D01*
X124400D01*
G01X139600Y415650D02*
Y421850D01*
X136400D01*
Y415650D01*
X139600D01*
G01X130100Y416400D02*
Y422600D01*
X126900D01*
Y416400D01*
X130100D01*
G01X130940Y434645D02*
X133543D01*
G01X136797D02*
X139545D01*
G01X136631Y439548D02*
X137589Y436448D01*
X138547Y439548D01*
G01X138202Y438463D02*
X136976D01*
G01X141149Y439548D02*
Y436448D01*
X139731Y438670D01*
X141647D01*
G01X143061Y436965D02*
X143291Y436655D01*
X143559Y436500D01*
X143866Y436448D01*
X144249Y436551D01*
X144517Y436810D01*
X144594Y437120D01*
X144556Y437430D01*
X144402Y437688D01*
X143636Y438205D01*
X143291Y438566D01*
X143061Y439083D01*
X142984Y439548D01*
X144594D01*
G01X152693Y-618936D02*
Y-626936D01*
X156693D01*
G01X164493D02*
Y-621603D01*
G01Y-622536D02*
X164093Y-622003D01*
X163493Y-621736D01*
X162793Y-621603D01*
X162093Y-621869D01*
X161493Y-622403D01*
X161093Y-623203D01*
X160893Y-624269D01*
X161093Y-625336D01*
X161493Y-626136D01*
X162093Y-626669D01*
X162793Y-626936D01*
X163493Y-626803D01*
X164093Y-626403D01*
X164493Y-625870D01*
G01X168593Y-629336D02*
X169193Y-629603D01*
X169993Y-629336D01*
X170493Y-628803D01*
X170893Y-628136D01*
X171493Y-626003D01*
X172793Y-621603D01*
G01X169593D02*
X171493Y-626003D01*
G01X177193Y-623336D02*
X180393D01*
X180093Y-622403D01*
X179593Y-621869D01*
X178893Y-621603D01*
X178193Y-621736D01*
X177593Y-622136D01*
X177193Y-623069D01*
X176993Y-623870D01*
Y-624669D01*
X177193Y-625469D01*
X177693Y-626269D01*
X178293Y-626803D01*
X178993Y-626936D01*
X179693Y-626669D01*
X180393Y-625870D01*
G01X185293Y-626936D02*
Y-621603D01*
G01Y-622669D02*
X185793Y-622136D01*
X186293Y-621736D01*
X186993Y-621603D01*
X187493Y-621736D01*
X188093Y-622136D01*
G01X146200Y10900D02*
Y21500D01*
X155600D01*
Y10900D01*
X146300D01*
G01X138200Y77100D02*
X144400D01*
Y80300D01*
X138200D01*
Y77100D01*
G01X139700Y121000D02*
X139800D01*
Y131000D01*
G01X146000Y126700D02*
Y131300D01*
G01X150500Y126700D02*
Y131300D01*
G01X140500Y126700D02*
Y131300D01*
G01X150500Y131200D02*
Y131300D01*
X140500D01*
G01Y126700D02*
X150500D01*
G01X145000D02*
Y131300D01*
G01X154560Y142656D02*
X148360D01*
Y139456D01*
X154560D01*
Y142656D01*
G01X143794Y151244D02*
X149994D01*
Y154444D01*
X143794D01*
Y151244D01*
G01X141100Y139400D02*
Y145600D01*
X137900D01*
Y139400D01*
X141100D01*
G01X158120Y177320D02*
X151920D01*
Y174120D01*
X158120D01*
Y177320D01*
G01X146600Y180510D02*
X152800D01*
Y183710D01*
X146600D01*
Y180510D01*
G01X145984Y191000D02*
X152184D01*
Y194200D01*
X145984D01*
Y191000D01*
G01X154050Y204694D02*
Y210894D01*
X150850D01*
Y204694D01*
X154050D01*
G01X156748Y223247D02*
X146548D01*
Y218647D01*
X156748D01*
Y223247D01*
G01X151648D02*
Y218647D01*
G01X150400Y257400D02*
Y251200D01*
X153600D01*
Y257400D01*
X150400D01*
G01Y264600D02*
Y258400D01*
X153600D01*
Y264600D01*
X150400D01*
G01X143600Y269057D02*
X141378D01*
X140913Y269210D01*
X140603Y269517D01*
X140500Y269900D01*
X140603Y270283D01*
X140913Y270590D01*
X141378Y270743D01*
X143600D01*
G01X143083Y272272D02*
X143393Y272502D01*
X143548Y272770D01*
X143600Y273077D01*
X143497Y273460D01*
X143238Y273728D01*
X142928Y273805D01*
X142618Y273767D01*
X142360Y273613D01*
X141843Y272847D01*
X141482Y272502D01*
X140965Y272272D01*
X140500Y272195D01*
Y273805D01*
G01X143600Y276100D02*
X143497Y275793D01*
X143238Y275563D01*
X142928Y275410D01*
X142515Y275295D01*
X142050Y275257D01*
X141585Y275295D01*
X141172Y275410D01*
X140862Y275563D01*
X140603Y275793D01*
X140500Y276100D01*
X140603Y276407D01*
X140862Y276637D01*
X141172Y276790D01*
X141585Y276905D01*
X142050Y276943D01*
X142515Y276905D01*
X142928Y276790D01*
X143238Y276637D01*
X143497Y276407D01*
X143600Y276100D01*
G01X138900Y264500D02*
Y258700D01*
G01Y272300D02*
Y266500D01*
G01X152077Y324528D02*
X158277D01*
Y327728D01*
X152077D01*
Y324528D01*
G01Y328564D02*
X158277D01*
Y331764D01*
X152077D01*
Y328564D01*
G01X149650Y360100D02*
Y366300D01*
X146450D01*
Y360100D01*
X149650D01*
G01X146693Y358600D02*
Y356378D01*
X146540Y355913D01*
X146233Y355603D01*
X145850Y355500D01*
X145467Y355603D01*
X145160Y355913D01*
X145007Y356378D01*
Y358600D01*
G01X143478Y358083D02*
X143248Y358393D01*
X142980Y358548D01*
X142673Y358600D01*
X142290Y358497D01*
X142022Y358238D01*
X141945Y357928D01*
X141983Y357618D01*
X142137Y357360D01*
X142903Y356843D01*
X143248Y356482D01*
X143478Y355965D01*
X143555Y355500D01*
X141945D01*
G01X140378Y358083D02*
X140148Y358393D01*
X139880Y358548D01*
X139573Y358600D01*
X139190Y358497D01*
X138922Y358238D01*
X138845Y357928D01*
X138883Y357618D01*
X139037Y357360D01*
X139803Y356843D01*
X140148Y356482D01*
X140378Y355965D01*
X140455Y355500D01*
X138845D01*
G01X152910Y363169D02*
X151300D01*
G01X144150Y390400D02*
X150350D01*
Y393600D01*
X144150D01*
Y390400D01*
G01X141680Y377160D02*
X147880D01*
Y380360D01*
X141680D01*
Y377160D01*
G01Y381160D02*
X147880D01*
Y384360D01*
X141680D01*
Y381160D01*
G01X150350Y399100D02*
X144150D01*
Y395900D01*
X150350D01*
Y399100D01*
G01X144150Y400150D02*
X150350D01*
Y403350D01*
X144150D01*
Y400150D01*
G01X147600Y415650D02*
Y421850D01*
X144400D01*
Y415650D01*
X147600D01*
G01X151600D02*
Y421850D01*
X148400D01*
Y415650D01*
X151600D01*
G01X143600D02*
Y421850D01*
X140400D01*
Y415650D01*
X143600D01*
G01X155400Y415700D02*
Y421900D01*
X152200D01*
Y415700D01*
X155400D01*
G01X150350Y409600D02*
X144150D01*
Y406400D01*
X150350D01*
Y409600D01*
G01X142220Y434645D02*
X149900D01*
G01X164093Y-650870D02*
X164893Y-651536D01*
X165793Y-651936D01*
X166593D01*
X167393Y-651536D01*
X167993Y-650870D01*
X168293Y-649936D01*
X168093Y-649003D01*
X167593Y-648203D01*
X166693Y-647669D01*
X165493Y-647403D01*
X164793Y-646869D01*
X164493Y-645936D01*
X164693Y-645003D01*
X165193Y-644336D01*
X165893Y-643936D01*
X166593D01*
X167293Y-644203D01*
X167893Y-644869D01*
G01X172993Y-643936D02*
X175393D01*
G01X174193D02*
Y-651936D01*
G01X172993D02*
X175393D01*
G01X180193Y-643936D02*
Y-651936D01*
X184193D01*
G01X187993D02*
Y-643936D01*
G01X191793D02*
X187993Y-648870D01*
G01X192393Y-651936D02*
X189693Y-646603D01*
G01X196893Y-649269D02*
X199493D01*
G01X206993Y-647669D02*
X207393Y-647269D01*
X207693Y-646603D01*
X207893Y-645669D01*
X207693Y-644869D01*
X207293Y-644336D01*
X206593Y-643936D01*
X203893D01*
Y-651936D01*
X207193D01*
X207893Y-651403D01*
X208293Y-650603D01*
X208493Y-649669D01*
X208293Y-648736D01*
X207693Y-647936D01*
X206993Y-647669D01*
X203893D01*
G01X214193Y-651936D02*
X213393Y-651803D01*
X212693Y-651269D01*
X212093Y-650469D01*
X211693Y-649536D01*
X211493Y-648469D01*
Y-647403D01*
X211693Y-646336D01*
X212093Y-645403D01*
X212693Y-644603D01*
X213393Y-644069D01*
X214193Y-643936D01*
X214993Y-644069D01*
X215693Y-644603D01*
X216293Y-645403D01*
X216693Y-646336D01*
X216893Y-647403D01*
Y-648469D01*
X216693Y-649536D01*
X216293Y-650469D01*
X215693Y-651269D01*
X214993Y-651803D01*
X214193Y-651936D01*
G01X222193Y-643936D02*
Y-651936D01*
G01X219893Y-643936D02*
X224493D01*
G01X161800Y17300D02*
Y11100D01*
X165000D01*
Y17300D01*
X161800D01*
G01X166700Y10900D02*
Y21500D01*
X176100D01*
Y10900D01*
X166800D01*
G01X157100Y23400D02*
Y29600D01*
X153900D01*
Y23400D01*
X157100D01*
G01X153800Y117600D02*
X160000D01*
Y120800D01*
X153800D01*
Y117600D01*
G01X168333Y118226D02*
Y124426D01*
X165133D01*
Y118226D01*
X168333D01*
G01X161057Y124426D02*
Y118226D01*
X164257D01*
Y124426D01*
X161057D01*
G01X165117Y139469D02*
Y133269D01*
X168317D01*
Y139469D01*
X165117D01*
G01X163125Y151800D02*
X169325D01*
Y155000D01*
X163125D01*
Y151800D01*
G01X159100Y145400D02*
X165300D01*
Y148600D01*
X159100D01*
Y145400D01*
G01X158125Y148602D02*
Y154802D01*
X154925D01*
Y148602D01*
X158125D01*
G01X161900Y163900D02*
X168100D01*
Y167100D01*
X161900D01*
Y163900D01*
G01X169321Y158890D02*
X163121D01*
Y155690D01*
X169321D01*
Y158890D01*
G01X168450Y162750D02*
X162250D01*
Y159550D01*
X168450D01*
Y162750D01*
G01X161900Y167900D02*
X168100D01*
Y171100D01*
X161900D01*
Y167900D01*
G01X162100Y171600D02*
X168300D01*
Y174800D01*
X162100D01*
Y171600D01*
G01X168321Y183335D02*
X162121D01*
Y180135D01*
X168321D01*
Y183335D01*
G01X162121Y175285D02*
X168321D01*
Y178485D01*
X162121D01*
Y175285D01*
G01X154105Y179973D02*
X160305D01*
Y183173D01*
X154105D01*
Y179973D01*
G01X168321Y187552D02*
X162121D01*
Y184352D01*
X168321D01*
Y187552D01*
G01Y192325D02*
X162121D01*
Y189125D01*
X168321D01*
Y192325D01*
G01X160308Y190682D02*
X154108D01*
Y187482D01*
X160308D01*
Y190682D01*
G01Y194182D02*
X154108D01*
Y190982D01*
X160308D01*
Y194182D01*
G01X154108Y183982D02*
X160308D01*
Y187182D01*
X154108D01*
Y183982D01*
G01X158884Y204705D02*
X165084D01*
Y207905D01*
X158884D01*
Y204705D01*
G01X158067Y204694D02*
Y210894D01*
X154867D01*
Y204694D01*
X158067D01*
G01X157884Y200705D02*
X164084D01*
Y203905D01*
X157884D01*
Y200705D01*
G01X173530Y213633D02*
X167330D01*
Y210433D01*
X173530D01*
Y213633D01*
G01X163724Y220006D02*
Y215406D01*
G01Y215506D02*
Y215406D01*
X173724D01*
G01Y220006D02*
X163724D01*
G01X171200Y230000D02*
X165000D01*
Y226800D01*
X171200D01*
Y230000D01*
G01X160764Y219089D02*
Y225289D01*
X157564D01*
Y219089D01*
X160764D01*
G01X166700Y235400D02*
Y230800D01*
G01X162200Y235400D02*
Y230800D01*
G01Y230900D02*
Y230800D01*
X172200D01*
G01Y235400D02*
X162200D01*
G01Y230332D02*
X156000D01*
Y227132D01*
X162200D01*
Y230332D01*
G01X159825Y233900D02*
X153625D01*
Y230700D01*
X159825D01*
Y233900D01*
G01X159191Y244229D02*
X152991D01*
Y241029D01*
X159191D01*
Y244229D01*
G01X168132Y240079D02*
X161932D01*
Y236879D01*
X168132D01*
Y240079D01*
G01X161530Y234510D02*
Y240710D01*
X158330D01*
Y234510D01*
X161530D01*
G01X162365Y255863D02*
Y262063D01*
X159165D01*
Y255863D01*
X162365D01*
G01X158295Y255875D02*
Y262075D01*
X155095D01*
Y255875D01*
X158295D01*
G01X166401Y255861D02*
Y262061D01*
X163201D01*
Y255861D01*
X166401D01*
G01X162573Y247911D02*
Y254111D01*
X159373D01*
Y247911D01*
X162573D01*
G01X158563D02*
Y254111D01*
X155363D01*
Y247911D01*
X158563D01*
G01X166613D02*
Y254111D01*
X163413D01*
Y247911D01*
X166613D01*
G01X172034Y283448D02*
X165834D01*
Y280248D01*
X172034D01*
Y283448D01*
G01X165700Y284662D02*
X178704D01*
Y297662D01*
X167700D01*
G01X161300Y293400D02*
X161607Y293452D01*
X161875Y293658D01*
X162105Y293968D01*
X162258Y294330D01*
X162335Y294743D01*
Y295157D01*
X162258Y295570D01*
X162105Y295932D01*
X161875Y296242D01*
X161607Y296448D01*
X161300Y296500D01*
X160993Y296448D01*
X160725Y296242D01*
X160495Y295932D01*
X160342Y295570D01*
X160265Y295157D01*
Y294743D01*
X160342Y294330D01*
X160495Y293968D01*
X160725Y293658D01*
X160993Y293452D01*
X161300Y293400D01*
G01X160993Y294227D02*
X160533Y293400D01*
G01X158200D02*
Y296500D01*
X158660Y295880D01*
G01Y293400D02*
X157740D01*
G01X155100D02*
Y296500D01*
X155560Y295880D01*
G01Y293400D02*
X154640D01*
G01X163904Y294100D02*
Y288000D01*
G01X159577Y324540D02*
X172577D01*
Y339540D01*
X159577D01*
Y324540D01*
G01X155102Y356416D02*
X154893Y356602D01*
X154810Y356816D01*
X154893Y357029D01*
X155143Y357216D01*
X155518Y357349D01*
X155893Y357402D01*
X156352D01*
X156727Y357349D01*
X157060Y357216D01*
X157227Y357056D01*
X157310Y356869D01*
X157227Y356656D01*
X157060Y356496D01*
X156810Y356389D01*
X156477Y356336D01*
X156185Y356389D01*
X155893Y356522D01*
X155727Y356682D01*
X155685Y356869D01*
X155768Y357082D01*
X155977Y357242D01*
X156352Y357402D01*
G01X164110Y357869D02*
Y355869D01*
G01X155110Y359051D02*
X154055D01*
G01X155110D02*
X154055D01*
G01D02*
Y362069D01*
G01X156000Y371300D02*
X158500D01*
X158000Y370980D01*
G01X156000D02*
Y371620D01*
G01X158083Y372993D02*
X158333Y373153D01*
X158458Y373340D01*
X158500Y373553D01*
X158417Y373820D01*
X158208Y374007D01*
X157958Y374060D01*
X157708Y374033D01*
X157500Y373927D01*
X157083Y373393D01*
X156792Y373153D01*
X156375Y372993D01*
X156000Y372940D01*
Y374060D01*
G01X162110Y370469D02*
Y372469D01*
G01X154055Y366269D02*
Y369287D01*
X155110D01*
G01X173943Y388550D02*
Y386328D01*
X173790Y385863D01*
X173483Y385553D01*
X173100Y385450D01*
X172717Y385553D01*
X172410Y385863D01*
X172257Y386328D01*
Y388550D01*
G01X170728Y388033D02*
X170498Y388343D01*
X170230Y388498D01*
X169923Y388550D01*
X169540Y388447D01*
X169272Y388188D01*
X169195Y387878D01*
X169233Y387568D01*
X169387Y387310D01*
X170153Y386793D01*
X170498Y386432D01*
X170728Y385915D01*
X170805Y385450D01*
X169195D01*
G01X166900D02*
Y388550D01*
X167360Y387930D01*
G01Y385450D02*
X166440D01*
G01X164896Y410505D02*
Y390305D01*
X180696D01*
Y410505D01*
X175096D01*
X172796Y408205D01*
X170496Y410505D01*
X164896D01*
G01X159200Y415700D02*
Y421900D01*
X156000D01*
Y415700D01*
X159200D01*
G01X165700Y415807D02*
X163478D01*
X163013Y415960D01*
X162703Y416267D01*
X162600Y416650D01*
X162703Y417033D01*
X163013Y417340D01*
X163478Y417493D01*
X165700D01*
G01X162600Y420210D02*
X165700D01*
X163478Y418792D01*
Y420708D01*
G01X162600Y422850D02*
X162652Y423118D01*
X162807Y423425D01*
X163065Y423617D01*
X163427Y423693D01*
X163788Y423617D01*
X164098Y423387D01*
X164253Y423042D01*
Y422658D01*
X164357Y422428D01*
X164615Y422237D01*
X164977Y422160D01*
X165338Y422275D01*
X165597Y422543D01*
X165700Y422850D01*
X165597Y423157D01*
X165338Y423425D01*
X164977Y423540D01*
X164615Y423463D01*
X164357Y423272D01*
X164253Y423042D01*
Y422658D01*
X164098Y422313D01*
X163788Y422083D01*
X163427Y422007D01*
X163065Y422083D01*
X162807Y422275D01*
X162652Y422582D01*
X162600Y422850D01*
G01X179337Y412594D02*
X166863D01*
Y424406D01*
X179337D01*
Y412594D01*
G01X153900Y434645D02*
X163000D01*
G01X165531Y439548D02*
X166489Y436448D01*
X167447Y439548D01*
G01X167102Y438463D02*
X165876D01*
G01X168861Y436965D02*
X169091Y436655D01*
X169359Y436500D01*
X169666Y436448D01*
X170049Y436551D01*
X170317Y436810D01*
X170394Y437120D01*
X170356Y437430D01*
X170202Y437688D01*
X169436Y438205D01*
X169091Y438566D01*
X168861Y439083D01*
X168784Y439548D01*
X170394D01*
G01X172037Y439186D02*
X172306Y439445D01*
X172612Y439548D01*
X172919Y439445D01*
X173187Y439135D01*
X173379Y438670D01*
X173456Y438205D01*
Y437636D01*
X173379Y437171D01*
X173187Y436758D01*
X172957Y436551D01*
X172689Y436448D01*
X172382Y436551D01*
X172152Y436758D01*
X171999Y437068D01*
X171922Y437481D01*
X171999Y437843D01*
X172191Y438205D01*
X172421Y438411D01*
X172689Y438463D01*
X172996Y438360D01*
X173226Y438101D01*
X173456Y437636D01*
G01X173993Y-676936D02*
Y-668936D01*
G01X177793D02*
X173993Y-673870D01*
G01X178393Y-676936D02*
X175693Y-671603D01*
G01X185993Y-676936D02*
Y-671603D01*
G01Y-672536D02*
X185593Y-672003D01*
X184993Y-671736D01*
X184293Y-671603D01*
X183593Y-671869D01*
X182993Y-672403D01*
X182593Y-673203D01*
X182393Y-674269D01*
X182593Y-675336D01*
X182993Y-676136D01*
X183593Y-676669D01*
X184293Y-676936D01*
X184993Y-676803D01*
X185593Y-676403D01*
X185993Y-675870D01*
G01X192193Y-671603D02*
Y-676936D01*
G01Y-669469D02*
X191993Y-669336D01*
Y-669069D01*
X192193Y-668936D01*
X192393Y-669069D01*
Y-669336D01*
X192193Y-669469D01*
G01X181000Y13100D02*
Y19300D01*
X177800D01*
Y13100D01*
X181000D01*
G01X171100Y22900D02*
Y29100D01*
X167900D01*
Y22900D01*
X171100D01*
G01X180493Y25967D02*
Y23745D01*
X180340Y23280D01*
X180033Y22970D01*
X179650Y22867D01*
X179267Y22970D01*
X178960Y23280D01*
X178807Y23745D01*
Y25967D01*
G01X177278Y25450D02*
X177048Y25760D01*
X176780Y25915D01*
X176473Y25967D01*
X176090Y25864D01*
X175822Y25605D01*
X175745Y25295D01*
X175783Y24985D01*
X175937Y24727D01*
X176703Y24210D01*
X177048Y23849D01*
X177278Y23332D01*
X177355Y22867D01*
X175745D01*
G01X174178Y24159D02*
X173910Y24520D01*
X173680Y24727D01*
X173373Y24830D01*
X173105Y24727D01*
X172913Y24520D01*
X172760Y24210D01*
X172722Y23849D01*
X172760Y23539D01*
X172913Y23229D01*
X173143Y22970D01*
X173412Y22867D01*
X173718Y22970D01*
X173987Y23280D01*
X174140Y23745D01*
X174178Y24262D01*
X174102Y24934D01*
X173987Y25295D01*
X173795Y25657D01*
X173527Y25915D01*
X173258Y25967D01*
X172990Y25864D01*
X172798Y25605D01*
G01X188493Y75900D02*
Y73678D01*
X188340Y73213D01*
X188033Y72903D01*
X187650Y72800D01*
X187267Y72903D01*
X186960Y73213D01*
X186807Y73678D01*
Y75900D01*
G01X185278Y75383D02*
X185048Y75693D01*
X184780Y75848D01*
X184473Y75900D01*
X184090Y75797D01*
X183822Y75538D01*
X183745Y75228D01*
X183783Y74918D01*
X183937Y74660D01*
X184703Y74143D01*
X185048Y73782D01*
X185278Y73265D01*
X185355Y72800D01*
X183745D01*
G01X182293Y73420D02*
X182063Y73058D01*
X181757Y72852D01*
X181412Y72800D01*
X181105Y72852D01*
X180798Y73110D01*
X180607Y73420D01*
X180568Y73730D01*
X180645Y74092D01*
X180913Y74350D01*
X181182Y74453D01*
X181527D01*
G01X181182D02*
X180952Y74608D01*
X180760Y74867D01*
X180683Y75177D01*
X180760Y75487D01*
X180952Y75745D01*
X181297Y75900D01*
X181642Y75848D01*
X181987Y75642D01*
G01X183079Y80210D02*
X180477Y77608D01*
X176255D01*
Y89812D01*
X189903D01*
Y77608D01*
X185681D01*
X183079Y80210D01*
G01X170600Y73400D02*
Y79600D01*
X167400D01*
Y73400D01*
X170600D01*
G01X171400Y79600D02*
Y73400D01*
X174600D01*
Y79600D01*
X171400D01*
G01X180360Y98050D02*
Y91850D01*
X183560D01*
Y98050D01*
X180360D01*
G01X172338Y118226D02*
Y124426D01*
X169138D01*
Y118226D01*
X172338D01*
G01X180361D02*
Y124426D01*
X177161D01*
Y118226D01*
X180361D01*
G01X176341D02*
Y124426D01*
X173141D01*
Y118226D01*
X176341D01*
G01X169137Y139469D02*
Y133269D01*
X172337D01*
Y139469D01*
X169137D01*
G01X181354D02*
Y133269D01*
X184554D01*
Y139469D01*
X181354D01*
G01X173140D02*
Y133269D01*
X176340D01*
Y139469D01*
X173140D01*
G01X177216D02*
Y133269D01*
X180416D01*
Y139469D01*
X177216D01*
G01X183141Y208531D02*
Y214731D01*
X179941D01*
Y208531D01*
X183141D01*
G01X168224Y220006D02*
Y215406D01*
G01X173724Y220006D02*
Y215406D01*
G01X169224Y220006D02*
Y215406D01*
G01X175700Y221400D02*
Y215200D01*
X178900D01*
Y221400D01*
X175700D01*
G01X172200Y235400D02*
Y230800D01*
G01X167700Y235400D02*
Y230800D01*
G01X179100Y241000D02*
Y247200D01*
X175900D01*
Y241000D01*
X179100D01*
G01X168100Y247900D02*
Y241700D01*
X171300D01*
Y247900D01*
X168100D01*
G01X175200Y241000D02*
Y247200D01*
X172000D01*
Y241000D01*
X175200D01*
G01X180277Y236844D02*
X186477D01*
Y240044D01*
X180277D01*
Y236844D01*
G01X179700Y247100D02*
Y240900D01*
X182900D01*
Y247100D01*
X179700D01*
G01X175592Y255731D02*
Y261931D01*
X172392D01*
Y255731D01*
X175592D01*
G01X171534Y255733D02*
Y261933D01*
X168334D01*
Y255733D01*
X171534D01*
G01X174100Y268600D02*
X167900D01*
Y265400D01*
X174100D01*
Y268600D01*
G01X181800Y277600D02*
X188000D01*
Y280800D01*
X181800D01*
Y277600D01*
G01X169690Y299300D02*
X175890D01*
Y302500D01*
X169690D01*
Y299300D01*
G01X176850Y329157D02*
X174628D01*
X174163Y329310D01*
X173853Y329617D01*
X173750Y330000D01*
X173853Y330383D01*
X174163Y330690D01*
X174628Y330843D01*
X176850D01*
G01X173750Y333100D02*
X176850D01*
X176230Y332640D01*
G01X173750D02*
Y333560D01*
G01Y336200D02*
X176850D01*
X176230Y335740D01*
G01X173750D02*
Y336660D01*
G01X171200Y351500D02*
Y345300D01*
X174400D01*
Y351500D01*
X171200D01*
G01X178300Y345300D02*
Y351500D01*
X175100D01*
Y345300D01*
X178300D01*
G01X176400Y343425D02*
Y337225D01*
X179600D01*
Y343425D01*
X176400D01*
G01X171393Y356462D02*
X171643Y356622D01*
X171768Y356809D01*
X171810Y357022D01*
X171727Y357289D01*
X171518Y357476D01*
X171268Y357529D01*
X171018Y357502D01*
X170810Y357396D01*
X170393Y356862D01*
X170102Y356622D01*
X169685Y356462D01*
X169310Y356409D01*
Y357529D01*
G01X172165Y362069D02*
Y359051D01*
X171110D01*
G01X183000Y361200D02*
Y367400D01*
X179800D01*
Y361200D01*
X183000D01*
G01X179100D02*
Y367400D01*
X175900D01*
Y361200D01*
X179100D01*
G01X170000Y374300D02*
X172500D01*
X172000Y373980D01*
G01X170000D02*
Y374620D01*
G01X170292Y376047D02*
X170083Y376233D01*
X170000Y376447D01*
X170083Y376660D01*
X170333Y376847D01*
X170708Y376980D01*
X171083Y377033D01*
X171542D01*
X171917Y376980D01*
X172250Y376847D01*
X172417Y376687D01*
X172500Y376500D01*
X172417Y376287D01*
X172250Y376127D01*
X172000Y376020D01*
X171667Y375967D01*
X171375Y376020D01*
X171083Y376153D01*
X170917Y376313D01*
X170875Y376500D01*
X170958Y376713D01*
X171167Y376873D01*
X171542Y377033D01*
G01X173310Y365169D02*
X175400D01*
G01X171110Y369287D02*
X172165D01*
Y366269D01*
G01X180100Y378100D02*
Y384300D01*
X176900D01*
Y378100D01*
X180100D01*
G01X184100D02*
Y384300D01*
X180900D01*
Y378100D01*
X184100D01*
G01X176900Y384300D02*
Y378100D01*
X180100D01*
Y384300D01*
X176900D01*
G01X180900D02*
Y378100D01*
X184100D01*
Y384300D01*
X180900D01*
G01X181000Y419550D02*
Y413350D01*
X184200D01*
Y419550D01*
X181000D01*
G01X186600Y424400D02*
X180400D01*
Y421200D01*
X186600D01*
Y424400D01*
G01X167700Y434645D02*
X170200D01*
G01X174800D02*
X206000D01*
G01X187070Y91850D02*
Y98050D01*
X183870D01*
Y91850D01*
X187070D01*
G01X190580Y91860D02*
Y98060D01*
X187380D01*
Y91860D01*
X190580D01*
G01X196430Y78460D02*
Y84660D01*
X193230D01*
Y78460D01*
X196430D01*
G01X189031Y118387D02*
Y124587D01*
X185831D01*
Y118387D01*
X189031D01*
G01X193034D02*
Y124587D01*
X189834D01*
Y118387D01*
X193034D01*
G01X197100Y118400D02*
Y124600D01*
X193900D01*
Y118400D01*
X197100D01*
G01X197600Y110400D02*
Y116600D01*
X194400D01*
Y110400D01*
X197600D01*
G01X185400Y139600D02*
Y133400D01*
X188600D01*
Y139600D01*
X185400D01*
G01X192600Y133400D02*
Y139600D01*
X189400D01*
Y133400D01*
X192600D01*
G01X196600D02*
Y139600D01*
X193400D01*
Y133400D01*
X196600D01*
G01X197932Y142316D02*
Y148516D01*
X194732D01*
Y142316D01*
X197932D01*
G01X199063Y167388D02*
Y173588D01*
X195863D01*
Y167388D01*
X199063D01*
G01X191743Y183086D02*
Y176886D01*
X194943D01*
Y183086D01*
X191743D01*
G01X191950Y176276D02*
Y170076D01*
X195150D01*
Y176276D01*
X191950D01*
G01X195753Y180369D02*
X201953D01*
Y183569D01*
X195753D01*
Y180369D01*
G01X189196Y185735D02*
Y191935D01*
X185996D01*
Y185735D01*
X189196D01*
G01X189481Y195943D02*
X183281D01*
Y192743D01*
X189481D01*
Y195943D01*
G01X195324Y184580D02*
Y190780D01*
X192124D01*
Y184580D01*
X195324D01*
G01X196167Y192997D02*
Y199197D01*
X192967D01*
Y192997D01*
X196167D01*
G01X190100Y202200D02*
Y208400D01*
X186900D01*
Y202200D01*
X190100D01*
G01X191900Y211600D02*
X198100D01*
Y214800D01*
X191900D01*
Y211600D01*
G01X191800Y208100D02*
X198000D01*
Y211300D01*
X191800D01*
Y208100D01*
G01Y204600D02*
X198000D01*
Y207800D01*
X191800D01*
Y204600D01*
G01X187693Y215608D02*
X193893D01*
Y218808D01*
X187693D01*
Y215608D01*
G01X200898Y218808D02*
X194698D01*
Y215608D01*
X200898D01*
Y218808D01*
G01X189093Y247653D02*
Y241453D01*
X192293D01*
Y247653D01*
X189093D01*
G01X193129D02*
Y241453D01*
X196329D01*
Y247653D01*
X193129D01*
G01X183290Y247115D02*
Y240915D01*
X186490D01*
Y247115D01*
X183290D01*
G01X196085Y233938D02*
Y240138D01*
X192885D01*
Y233938D01*
X196085D01*
G01X190901Y254857D02*
Y248657D01*
X194101D01*
Y254857D01*
X190901D01*
G01X186900Y254850D02*
Y248650D01*
X190100D01*
Y254850D01*
X186900D01*
G01X196190Y276318D02*
Y270118D01*
X199390D01*
Y276318D01*
X196190D01*
G01X199600Y259550D02*
Y265750D01*
X196400D01*
Y259550D01*
X199600D01*
G01X185590Y265400D02*
X191790D01*
Y268600D01*
X185590D01*
Y265400D01*
G01X185470Y264010D02*
Y257810D01*
X188670D01*
Y264010D01*
X185470D01*
G01X192500Y265780D02*
Y259580D01*
X195700D01*
Y265780D01*
X192500D01*
G01X203331Y288381D02*
X197131D01*
Y285181D01*
X203331D01*
Y288381D01*
G01X197131Y277143D02*
X203331D01*
Y280343D01*
X197131D01*
Y277143D01*
G01X185305Y281555D02*
X191505D01*
Y284755D01*
X185305D01*
Y281555D01*
G01X197131Y281173D02*
X203331D01*
Y284373D01*
X197131D01*
Y281173D01*
G01X185305Y285621D02*
X191505D01*
Y288821D01*
X185305D01*
Y285621D01*
G01X191486Y296696D02*
X185286D01*
Y293496D01*
X191486D01*
Y296696D01*
G01X185273Y289572D02*
X191473D01*
Y292772D01*
X185273D01*
Y289572D01*
G01X189800Y301900D02*
X183600D01*
Y298700D01*
X189800D01*
Y301900D01*
G01X200579Y304704D02*
Y324904D01*
X184779D01*
Y304704D01*
X190379D01*
X192679Y307004D01*
X194979Y304704D01*
X200579D01*
G01X185620Y350600D02*
Y344400D01*
X188820D01*
Y350600D01*
X185620D01*
G01X195400Y343800D02*
Y350000D01*
X192200D01*
Y343800D01*
X195400D01*
G01X192950Y408650D02*
X199150D01*
Y411850D01*
X192950D01*
Y408650D01*
G01X183931Y439548D02*
X184889Y436448D01*
X185847Y439548D01*
G01X185502Y438463D02*
X184276D01*
G01X187261Y436965D02*
X187491Y436655D01*
X187759Y436500D01*
X188066Y436448D01*
X188449Y436551D01*
X188717Y436810D01*
X188794Y437120D01*
X188756Y437430D01*
X188602Y437688D01*
X187836Y438205D01*
X187491Y438566D01*
X187261Y439083D01*
X187184Y439548D01*
X188794D01*
G01X191089D02*
X191357Y439496D01*
X191664Y439341D01*
X191856Y439083D01*
X191932Y438721D01*
X191856Y438360D01*
X191626Y438050D01*
X191281Y437895D01*
X190897D01*
X190667Y437791D01*
X190476Y437533D01*
X190399Y437171D01*
X190514Y436810D01*
X190782Y436551D01*
X191089Y436448D01*
X191396Y436551D01*
X191664Y436810D01*
X191779Y437171D01*
X191702Y437533D01*
X191511Y437791D01*
X191281Y437895D01*
X190897D01*
X190552Y438050D01*
X190322Y438360D01*
X190246Y438721D01*
X190322Y439083D01*
X190514Y439341D01*
X190821Y439496D01*
X191089Y439548D01*
G01X205600Y118400D02*
Y124600D01*
X202400D01*
Y118400D01*
X205600D01*
G01X209400D02*
Y124600D01*
X206200D01*
Y118400D01*
X209400D01*
G01X201100D02*
Y124600D01*
X197900D01*
Y118400D01*
X201100D01*
G01X212970Y118420D02*
Y124620D01*
X209770D01*
Y118420D01*
X212970D01*
G01X201600Y110400D02*
Y116600D01*
X198400D01*
Y110400D01*
X201600D01*
G01X209200Y139469D02*
Y133269D01*
X212400D01*
Y139469D01*
X209200D01*
G01X200600Y133300D02*
Y139500D01*
X197400D01*
Y133300D01*
X200600D01*
G01X208600D02*
Y139500D01*
X205400D01*
Y133300D01*
X208600D01*
G01X201300Y139600D02*
Y133400D01*
X204500D01*
Y139600D01*
X201300D01*
G01X205312Y148789D02*
Y142589D01*
X208512D01*
Y148789D01*
X205312D01*
G01X206892Y170689D02*
X213092D01*
Y173889D01*
X206892D01*
Y170689D01*
G01X213856Y179869D02*
X207656D01*
Y176669D01*
X213856D01*
Y179869D01*
G01X198693Y176369D02*
X204893D01*
Y179569D01*
X198693D01*
Y176369D01*
G01X206088Y173904D02*
X199888D01*
Y170704D01*
X206088D01*
Y173904D01*
G01X197586Y192815D02*
X203786D01*
Y196015D01*
X197586D01*
Y192815D01*
G01X211787Y196050D02*
X205587D01*
Y192850D01*
X211787D01*
Y196050D01*
G01X209894Y191734D02*
Y185534D01*
X213094D01*
Y191734D01*
X209894D01*
G01X209086Y184369D02*
Y190569D01*
X205886D01*
Y184369D01*
X209086D01*
G01X201065Y184400D02*
Y190600D01*
X197865D01*
Y184400D01*
X201065D01*
G01X205076Y184369D02*
Y190569D01*
X201876D01*
Y184369D01*
X205076D01*
G01X198890Y201910D02*
X205090D01*
Y205110D01*
X198890D01*
Y201910D01*
G01X211930Y205130D02*
X205730D01*
Y201930D01*
X211930D01*
Y205130D01*
G01X208272Y207784D02*
Y213984D01*
X205072D01*
Y207784D01*
X208272D01*
G01X201721Y214670D02*
X207921D01*
Y217870D01*
X201721D01*
Y214670D01*
G01X211933Y213955D02*
Y220155D01*
X208733D01*
Y213955D01*
X211933D01*
G01X214845Y237300D02*
Y243500D01*
X211645D01*
Y237300D01*
X214845D01*
G01X197314Y235655D02*
X203514D01*
Y238855D01*
X197314D01*
Y235655D01*
G01X197390Y246612D02*
Y240412D01*
X200590D01*
Y246612D01*
X197390D01*
G01X201390D02*
Y240412D01*
X204590D01*
Y246612D01*
X201390D01*
G01X204638Y239849D02*
Y233649D01*
X207838D01*
Y239849D01*
X204638D01*
G01X213700Y245700D02*
Y251900D01*
X210500D01*
Y245700D01*
X213700D01*
G01X198860Y254860D02*
Y248660D01*
X202060D01*
Y254860D01*
X198860D01*
G01X203392Y270118D02*
Y276318D01*
X200192D01*
Y270118D01*
X203392D01*
G01X202400Y265700D02*
Y259500D01*
X205600D01*
Y265700D01*
X202400D01*
G01X210100Y257300D02*
Y263500D01*
X206900D01*
Y257300D01*
X210100D01*
G01X211411Y270118D02*
Y276318D01*
X208211D01*
Y270118D01*
X211411D01*
G01X207410D02*
Y276318D01*
X204210D01*
Y270118D01*
X207410D01*
G01X205133Y285182D02*
X211333D01*
Y288382D01*
X205133D01*
Y285182D01*
G01X211333Y280339D02*
X205133D01*
Y277139D01*
X211333D01*
Y280339D01*
G01X203600Y302000D02*
X197400D01*
Y298800D01*
X203600D01*
Y302000D01*
G01X212200Y303600D02*
Y309800D01*
X209000D01*
Y303600D01*
X212200D01*
G01X205943Y330050D02*
Y327828D01*
X205790Y327363D01*
X205483Y327053D01*
X205100Y326950D01*
X204717Y327053D01*
X204410Y327363D01*
X204257Y327828D01*
Y330050D01*
G01X202843Y327570D02*
X202613Y327208D01*
X202307Y327002D01*
X201962Y326950D01*
X201655Y327002D01*
X201348Y327260D01*
X201157Y327570D01*
X201118Y327880D01*
X201195Y328242D01*
X201463Y328500D01*
X201732Y328603D01*
X202077D01*
G01X201732D02*
X201502Y328758D01*
X201310Y329017D01*
X201233Y329327D01*
X201310Y329637D01*
X201502Y329895D01*
X201847Y330050D01*
X202192Y329998D01*
X202537Y329792D01*
G01X198900Y330050D02*
X199207Y329947D01*
X199437Y329688D01*
X199590Y329378D01*
X199705Y328965D01*
X199743Y328500D01*
X199705Y328035D01*
X199590Y327622D01*
X199437Y327312D01*
X199207Y327053D01*
X198900Y326950D01*
X198593Y327053D01*
X198363Y327312D01*
X198210Y327622D01*
X198095Y328035D01*
X198057Y328500D01*
X198095Y328965D01*
X198210Y329378D01*
X198363Y329688D01*
X198593Y329947D01*
X198900Y330050D01*
G01X199150Y340650D02*
X205350D01*
Y343850D01*
X199150D01*
Y340650D01*
G01Y337150D02*
X205350D01*
Y340350D01*
X199150D01*
Y337150D01*
G01X198650Y344150D02*
X204850D01*
Y347350D01*
X198650D01*
Y344150D01*
G01Y354650D02*
X204850D01*
Y357850D01*
X198650D01*
Y354650D01*
G01Y351150D02*
X204850D01*
Y354350D01*
X198650D01*
Y351150D01*
G01Y347650D02*
X204850D01*
Y350850D01*
X198650D01*
Y347650D01*
G01Y358150D02*
X204850D01*
Y361350D01*
X198650D01*
Y358150D01*
G01Y361650D02*
X204850D01*
Y364850D01*
X198650D01*
Y361650D01*
G01Y365650D02*
X204850D01*
Y368850D01*
X198650D01*
Y365650D01*
G01Y369150D02*
X204850D01*
Y372350D01*
X198650D01*
Y369150D01*
G01X210000Y434645D02*
X218500D01*
G01X219900Y69100D02*
Y62900D01*
X223100D01*
Y69100D01*
X219900D01*
G01X237156Y67862D02*
X225344D01*
Y55238D01*
X237156D01*
Y67862D01*
G01X225800Y77700D02*
Y88300D01*
X235200D01*
Y77700D01*
X225900D01*
G01X229100Y91900D02*
Y98100D01*
X225900D01*
Y91900D01*
X229100D01*
G01X224550Y78557D02*
X222328D01*
X221863Y78710D01*
X221553Y79017D01*
X221450Y79400D01*
X221553Y79783D01*
X221863Y80090D01*
X222328Y80243D01*
X224550D01*
G01X224033Y81772D02*
X224343Y82002D01*
X224498Y82270D01*
X224550Y82577D01*
X224447Y82960D01*
X224188Y83228D01*
X223878Y83305D01*
X223568Y83267D01*
X223310Y83113D01*
X222793Y82347D01*
X222432Y82002D01*
X221915Y81772D01*
X221450Y81695D01*
Y83305D01*
G01X221812Y84948D02*
X221553Y85217D01*
X221450Y85523D01*
X221553Y85830D01*
X221863Y86098D01*
X222328Y86290D01*
X222793Y86367D01*
X223362D01*
X223827Y86290D01*
X224240Y86098D01*
X224447Y85868D01*
X224550Y85600D01*
X224447Y85293D01*
X224240Y85063D01*
X223930Y84910D01*
X223517Y84833D01*
X223155Y84910D01*
X222793Y85102D01*
X222587Y85332D01*
X222535Y85600D01*
X222638Y85907D01*
X222897Y86137D01*
X223362Y86367D01*
G01X228970Y118426D02*
Y124626D01*
X225770D01*
Y118426D01*
X228970D01*
G01X216894D02*
Y124626D01*
X213694D01*
Y118426D01*
X216894D01*
G01X224938D02*
Y124626D01*
X221738D01*
Y118426D01*
X224938D01*
G01X220913D02*
Y124626D01*
X217713D01*
Y118426D01*
X220913D01*
G01X212900Y139600D02*
Y133400D01*
X216100D01*
Y139600D01*
X212900D01*
G01X216900D02*
Y133400D01*
X220100D01*
Y139600D01*
X216900D01*
G01X220900D02*
Y133400D01*
X224100D01*
Y139600D01*
X220900D01*
G01X224900D02*
Y133400D01*
X228100D01*
Y139600D01*
X224900D01*
G01X213898Y173801D02*
Y167601D01*
X217098D01*
Y173801D01*
X213898D01*
G01X224581Y173940D02*
X218381D01*
Y170740D01*
X224581D01*
Y173940D01*
G01Y177946D02*
X218381D01*
Y174746D01*
X224581D01*
Y177946D01*
G01X228661Y171753D02*
Y177953D01*
X225461D01*
Y171753D01*
X228661D01*
G01X224877Y183492D02*
X218677D01*
Y180292D01*
X224877D01*
Y183492D01*
G01X214665Y184491D02*
Y178291D01*
X217865D01*
Y184491D01*
X214665D01*
G01X217558Y196321D02*
Y202521D01*
X214358D01*
Y196321D01*
X217558D01*
G01X226312Y195482D02*
X220112D01*
Y192282D01*
X226312D01*
Y195482D01*
G01X226749Y183338D02*
X232949D01*
Y186538D01*
X226749D01*
Y183338D01*
G01X220590Y190529D02*
Y184329D01*
X223790D01*
Y190529D01*
X220590D01*
G01X233195Y190538D02*
X226995D01*
Y187338D01*
X233195D01*
Y190538D01*
G01X218455Y185315D02*
Y191515D01*
X215255D01*
Y185315D01*
X218455D01*
G01X213112Y192321D02*
X219312D01*
Y195521D01*
X213112D01*
Y192321D01*
G01X213766Y213521D02*
Y203321D01*
X218366D01*
Y213521D01*
X213766D01*
G01Y208421D02*
X218366D01*
G01X227690Y202155D02*
X221490D01*
Y198955D01*
X227690D01*
Y202155D01*
G01X227444Y211743D02*
X221244D01*
Y208543D01*
X227444D01*
Y211743D01*
G01X227310Y206155D02*
X221110D01*
Y202955D01*
X227310D01*
Y206155D01*
G01X220121Y217630D02*
X213921D01*
Y214430D01*
X220121D01*
Y217630D01*
G01X220934Y214536D02*
X227134D01*
Y217736D01*
X220934D01*
Y214536D01*
G01X215600Y243300D02*
Y237100D01*
X218800D01*
Y243300D01*
X215600D01*
G01X221669Y242500D02*
Y236300D01*
X224869D01*
Y242500D01*
X221669D01*
G01X220400Y248960D02*
Y255160D01*
X217200D01*
Y248960D01*
X220400D01*
G01X225516Y254524D02*
Y248324D01*
X228716D01*
Y254524D01*
X225516D01*
G01X212500Y260300D02*
Y254100D01*
X215700D01*
Y260300D01*
X212500D01*
G01X221500Y253900D02*
Y247700D01*
X224700D01*
Y253900D01*
X221500D01*
G01X217900Y244200D02*
X224100D01*
Y247400D01*
X217900D01*
Y244200D01*
G01X212233Y272192D02*
Y265992D01*
X215433D01*
Y272192D01*
X212233D01*
G01X221500Y256800D02*
Y263000D01*
X218300D01*
Y256800D01*
X221500D01*
G01X226963Y257000D02*
Y263200D01*
X223763D01*
Y257000D01*
X226963D01*
G01X225000Y263900D02*
Y270100D01*
X221800D01*
Y263900D01*
X225000D01*
G01X218356Y288382D02*
X212156D01*
Y285182D01*
X218356D01*
Y288382D01*
G01Y284356D02*
X212156D01*
Y281156D01*
X218356D01*
Y284356D01*
G01X216262Y280337D02*
Y274137D01*
X219462D01*
Y280337D01*
X216262D01*
G01X212213Y280346D02*
Y274146D01*
X215413D01*
Y280346D01*
X212213D01*
G01X226966Y277373D02*
X220766D01*
Y274173D01*
X226966D01*
Y277373D01*
G01X220693Y288385D02*
Y282185D01*
X223893D01*
Y288385D01*
X220693D01*
G01X230993Y287512D02*
X224793D01*
Y284312D01*
X230993D01*
Y287512D01*
G01X220766Y278183D02*
X226966D01*
Y281383D01*
X220766D01*
Y278183D01*
G01X218720Y289194D02*
Y295394D01*
X215520D01*
Y289194D01*
X218720D01*
G01X224879Y292360D02*
X231079D01*
Y295560D01*
X224879D01*
Y292360D01*
G01X231079Y291541D02*
X224879D01*
Y288341D01*
X231079D01*
Y291541D01*
G01X219554Y295394D02*
Y289194D01*
X222754D01*
Y295394D01*
X219554D01*
G01X230443Y336550D02*
Y334328D01*
X230290Y333863D01*
X229983Y333553D01*
X229600Y333450D01*
X229217Y333553D01*
X228910Y333863D01*
X228757Y334328D01*
Y336550D01*
G01X226040Y333450D02*
Y336550D01*
X227458Y334328D01*
X225542D01*
G01X223400Y336550D02*
X223707Y336447D01*
X223937Y336188D01*
X224090Y335878D01*
X224205Y335465D01*
X224243Y335000D01*
X224205Y334535D01*
X224090Y334122D01*
X223937Y333812D01*
X223707Y333553D01*
X223400Y333450D01*
X223093Y333553D01*
X222863Y333812D01*
X222710Y334122D01*
X222595Y334535D01*
X222557Y335000D01*
X222595Y335465D01*
X222710Y335878D01*
X222863Y336188D01*
X223093Y336447D01*
X223400Y336550D01*
G01X219020Y368830D02*
Y337630D01*
X234820D01*
Y368830D01*
X229220D01*
X226920Y366530D01*
X224620Y368830D01*
X219020D01*
G01X225520Y371960D02*
Y378160D01*
X222320D01*
Y371960D01*
X225520D01*
G01X215352Y370529D02*
X221552D01*
Y373729D01*
X215352D01*
Y370529D01*
G01X223550Y392950D02*
X223857Y393002D01*
X224125Y393208D01*
X224355Y393518D01*
X224508Y393880D01*
X224585Y394293D01*
Y394707D01*
X224508Y395120D01*
X224355Y395482D01*
X224125Y395792D01*
X223857Y395998D01*
X223550Y396050D01*
X223243Y395998D01*
X222975Y395792D01*
X222745Y395482D01*
X222592Y395120D01*
X222515Y394707D01*
Y394293D01*
X222592Y393880D01*
X222745Y393518D01*
X222975Y393208D01*
X223243Y393002D01*
X223550Y392950D01*
G01X223243Y393777D02*
X222783Y392950D01*
G01X220450D02*
X220182Y393002D01*
X219875Y393157D01*
X219683Y393415D01*
X219607Y393777D01*
X219683Y394138D01*
X219913Y394448D01*
X220258Y394603D01*
X220642D01*
X220872Y394707D01*
X221063Y394965D01*
X221140Y395327D01*
X221025Y395688D01*
X220757Y395947D01*
X220450Y396050D01*
X220143Y395947D01*
X219875Y395688D01*
X219760Y395327D01*
X219837Y394965D01*
X220028Y394707D01*
X220258Y394603D01*
X220642D01*
X220987Y394448D01*
X221217Y394138D01*
X221293Y393777D01*
X221217Y393415D01*
X221025Y393157D01*
X220718Y393002D01*
X220450Y392950D01*
G01X217400Y418200D02*
Y424400D01*
X214200D01*
Y418200D01*
X217400D01*
G01X222500Y434645D02*
X228700D01*
G01X235850Y50200D02*
X236157Y50252D01*
X236425Y50458D01*
X236655Y50768D01*
X236808Y51130D01*
X236885Y51543D01*
Y51957D01*
X236808Y52370D01*
X236655Y52732D01*
X236425Y53042D01*
X236157Y53248D01*
X235850Y53300D01*
X235543Y53248D01*
X235275Y53042D01*
X235045Y52732D01*
X234892Y52370D01*
X234815Y51957D01*
Y51543D01*
X234892Y51130D01*
X235045Y50768D01*
X235275Y50458D01*
X235543Y50252D01*
X235850Y50200D01*
G01X235543Y51027D02*
X235083Y50200D01*
G01X233478Y51492D02*
X233210Y51853D01*
X232980Y52060D01*
X232673Y52163D01*
X232405Y52060D01*
X232213Y51853D01*
X232060Y51543D01*
X232022Y51182D01*
X232060Y50872D01*
X232213Y50562D01*
X232443Y50303D01*
X232712Y50200D01*
X233018Y50303D01*
X233287Y50613D01*
X233440Y51078D01*
X233478Y51595D01*
X233402Y52267D01*
X233287Y52628D01*
X233095Y52990D01*
X232827Y53248D01*
X232558Y53300D01*
X232290Y53197D01*
X232098Y52938D01*
G01X235600Y72600D02*
X229400D01*
Y69400D01*
X235600D01*
Y72600D01*
G01X246700Y73500D02*
X240500D01*
Y70300D01*
X246700D01*
Y73500D01*
G01X240300Y77700D02*
Y88300D01*
X249700D01*
Y77700D01*
X240400D01*
G01X240100Y98600D02*
Y92400D01*
X243300D01*
Y98600D01*
X240100D01*
G01X235100Y92400D02*
Y98600D01*
X231900D01*
Y92400D01*
X235100D01*
G01X233910Y124626D02*
Y118426D01*
X237110D01*
Y124626D01*
X233910D01*
G01X241190Y118426D02*
Y124626D01*
X237990D01*
Y118426D01*
X241190D01*
G01X233015D02*
Y124626D01*
X229815D01*
Y118426D01*
X233015D01*
G01X241100Y111360D02*
X234900D01*
Y108160D01*
X241100D01*
Y111360D01*
G01X243426Y133269D02*
Y139469D01*
X240226D01*
Y133269D01*
X243426D01*
G01X232900Y139800D02*
Y133600D01*
X236100D01*
Y139800D01*
X232900D01*
G01X228900Y139600D02*
Y133400D01*
X232100D01*
Y139600D01*
X228900D01*
G01X242800Y163800D02*
Y170000D01*
X239600D01*
Y163800D01*
X242800D01*
G01X232711Y171728D02*
Y177928D01*
X229511D01*
Y171728D01*
X232711D01*
G01X239554Y174182D02*
Y180382D01*
X236354D01*
Y174182D01*
X239554D01*
G01X233513Y170173D02*
X239713D01*
Y173373D01*
X233513D01*
Y170173D01*
G01X229351Y179266D02*
X235551D01*
Y182466D01*
X229351D01*
Y179266D01*
G01X243507Y184382D02*
X237307D01*
Y181182D01*
X243507D01*
Y184382D01*
G01X237554Y195751D02*
X231354D01*
Y192551D01*
X237554D01*
Y195751D01*
G01X236737Y202753D02*
Y196553D01*
X239937D01*
Y202753D01*
X236737D01*
G01X231113Y202760D02*
Y196560D01*
X234313D01*
Y202760D01*
X231113D01*
G01X244559Y195751D02*
X238359D01*
Y192551D01*
X244559D01*
Y195751D01*
G01X236425Y191466D02*
Y185266D01*
X239625D01*
Y191466D01*
X236425D01*
G01X230312Y191970D02*
Y198170D01*
X227112D01*
Y191970D01*
X230312D01*
G01X232621Y211137D02*
Y217337D01*
X229421D01*
Y211137D01*
X232621D01*
G01X241932Y206861D02*
X235732D01*
Y203661D01*
X241932D01*
Y206861D01*
G01X234308Y208640D02*
X228108D01*
Y205440D01*
X234308D01*
Y208640D01*
G01X236664Y211137D02*
Y217337D01*
X233464D01*
Y211137D01*
X236664D01*
G01X240664Y207662D02*
Y213862D01*
X237464D01*
Y207662D01*
X240664D01*
G01X228920Y243500D02*
Y237300D01*
X232120D01*
Y243500D01*
X228920D01*
G01X240013Y240439D02*
Y246639D01*
X236813D01*
Y240439D01*
X240013D01*
G01X243040Y247139D02*
X240830D01*
Y240939D01*
X242840D01*
G01X236700Y250200D02*
Y256400D01*
X233500D01*
Y250200D01*
X236700D01*
G01X240700Y249100D02*
Y255300D01*
X237500D01*
Y249100D01*
X240700D01*
G01X232850Y245850D02*
Y252050D01*
X229650D01*
Y245850D01*
X232850D01*
G01X244290Y256175D02*
Y262375D01*
X241090D01*
Y256175D01*
X244290D01*
G01X230865Y257323D02*
Y263523D01*
X227665D01*
Y257323D01*
X230865D01*
G01X237993Y285511D02*
X231793D01*
Y282311D01*
X237993D01*
Y285511D01*
G01X234953Y277441D02*
X228753D01*
Y274241D01*
X234953D01*
Y277441D01*
G01Y281453D02*
X228753D01*
Y278253D01*
X234953D01*
Y281453D01*
G01X236900Y308500D02*
X230700D01*
Y305300D01*
X236900D01*
Y308500D01*
G01X232300Y372500D02*
X238500D01*
Y375700D01*
X232300D01*
Y372500D01*
G01X237780Y376620D02*
X243980D01*
Y379820D01*
X237780D01*
Y376620D01*
G01X240312Y384094D02*
Y395906D01*
X227688D01*
Y384094D01*
X240312D01*
G01X241650Y397350D02*
Y391150D01*
X244850D01*
Y397350D01*
X241650D01*
G01X251400Y49900D02*
X257600D01*
Y53100D01*
X251400D01*
Y49900D01*
G01Y76600D02*
Y70400D01*
X254600D01*
Y76600D01*
X251400D01*
G01X249600Y92400D02*
Y98600D01*
X246400D01*
Y92400D01*
X249600D01*
G01X254100Y83207D02*
X251878D01*
X251413Y83360D01*
X251103Y83667D01*
X251000Y84050D01*
X251103Y84433D01*
X251413Y84740D01*
X251878Y84893D01*
X254100D01*
G01X251620Y86307D02*
X251258Y86537D01*
X251052Y86843D01*
X251000Y87188D01*
X251052Y87495D01*
X251310Y87802D01*
X251620Y87993D01*
X251930Y88032D01*
X252292Y87955D01*
X252550Y87687D01*
X252653Y87418D01*
Y87073D01*
G01Y87418D02*
X252808Y87648D01*
X253067Y87840D01*
X253377Y87917D01*
X253687Y87840D01*
X253945Y87648D01*
X254100Y87303D01*
X254048Y86958D01*
X253842Y86613D01*
G01X252292Y89522D02*
X252653Y89790D01*
X252860Y90020D01*
X252963Y90327D01*
X252860Y90595D01*
X252653Y90787D01*
X252343Y90940D01*
X251982Y90978D01*
X251672Y90940D01*
X251362Y90787D01*
X251103Y90557D01*
X251000Y90288D01*
X251103Y89982D01*
X251413Y89713D01*
X251878Y89560D01*
X252395Y89522D01*
X253067Y89598D01*
X253428Y89713D01*
X253790Y89905D01*
X254048Y90173D01*
X254100Y90442D01*
X253997Y90710D01*
X253738Y90902D01*
G01X242482Y112848D02*
Y106648D01*
X245682D01*
Y112848D01*
X242482D01*
G01X249100Y120400D02*
Y126600D01*
X245900D01*
Y120400D01*
X249100D01*
G01X254500Y114700D02*
Y108500D01*
X257700D01*
Y114700D01*
X254500D01*
G01X257933Y118426D02*
Y124626D01*
X254733D01*
Y118426D01*
X257933D01*
G01X245209Y118465D02*
Y124665D01*
X242009D01*
Y118465D01*
X245209D01*
G01X249687Y108539D02*
Y114739D01*
X246487D01*
Y108539D01*
X249687D01*
G01X253711D02*
Y114739D01*
X250511D01*
Y108539D01*
X253711D01*
G01X253974Y133269D02*
Y139469D01*
X250774D01*
Y133269D01*
X253974D01*
G01X244236Y139469D02*
Y133269D01*
X247436D01*
Y139469D01*
X244236D01*
G01X251000Y130900D02*
Y124700D01*
X254200D01*
Y130900D01*
X251000D01*
G01X255100Y139469D02*
Y133269D01*
X258300D01*
Y139469D01*
X255100D01*
G01X258196Y160351D02*
X251996D01*
Y157151D01*
X258196D01*
Y160351D01*
G01X245443Y193172D02*
X251643D01*
Y196372D01*
X245443D01*
Y193172D01*
G01X257676Y204697D02*
X251476D01*
Y201497D01*
X257676D01*
Y204697D01*
G01X246100Y211900D02*
Y218100D01*
X242900D01*
Y211900D01*
X246100D01*
G01Y204900D02*
Y211100D01*
X242900D01*
Y204900D01*
X246100D01*
G01X252065Y241053D02*
Y247253D01*
X248865D01*
Y241053D01*
X252065D01*
G01X256066Y241143D02*
Y247343D01*
X252866D01*
Y241143D01*
X256066D01*
G01X248030Y240939D02*
Y247139D01*
X245970D01*
G01X246200Y240939D02*
X248030D01*
G01X244030Y242110D02*
Y245930D01*
G01X244830Y246170D02*
Y242160D01*
G01X254927Y282378D02*
X248727D01*
Y279178D01*
X254927D01*
Y282378D01*
G01X255900Y278600D02*
Y272400D01*
X259100D01*
Y278600D01*
X255900D01*
G01X248727Y275156D02*
X254927D01*
Y278356D01*
X248727D01*
Y275156D01*
G01X248700Y349600D02*
X254900D01*
Y352800D01*
X248700D01*
Y349600D01*
G01X254900Y360700D02*
X248700D01*
Y357500D01*
X254900D01*
Y360700D01*
G01Y356800D02*
X248700D01*
Y353600D01*
X254900D01*
Y356800D01*
G01X248700Y372400D02*
Y366200D01*
X251900D01*
Y372400D01*
X248700D01*
G01Y361500D02*
X254900D01*
Y364700D01*
X248700D01*
Y361500D01*
G01X256510Y373300D02*
X254147Y375247D01*
Y380524D01*
X266353D01*
Y366076D01*
X254147D01*
Y371353D01*
X256510Y373300D01*
G01X252050Y380950D02*
X252357Y381002D01*
X252625Y381208D01*
X252855Y381518D01*
X253008Y381880D01*
X253085Y382293D01*
Y382707D01*
X253008Y383120D01*
X252855Y383482D01*
X252625Y383792D01*
X252357Y383998D01*
X252050Y384050D01*
X251743Y383998D01*
X251475Y383792D01*
X251245Y383482D01*
X251092Y383120D01*
X251015Y382707D01*
Y382293D01*
X251092Y381880D01*
X251245Y381518D01*
X251475Y381208D01*
X251743Y381002D01*
X252050Y380950D01*
G01X251743Y381777D02*
X251283Y380950D01*
G01X249793Y381415D02*
X249563Y381157D01*
X249295Y381002D01*
X248950Y380950D01*
X248605Y381053D01*
X248337Y381260D01*
X248145Y381622D01*
X248107Y382035D01*
X248183Y382448D01*
X248375Y382707D01*
X248643Y382913D01*
X248912Y382965D01*
X249180Y382913D01*
X249525Y382707D01*
X249410Y384050D01*
X248375D01*
G01X254310Y382100D02*
X264510D01*
Y386700D01*
X254310D01*
Y382100D01*
G01X263468Y400731D02*
X250994D01*
Y388763D01*
X263468D01*
Y400731D01*
G01X248350Y399000D02*
X248657Y399052D01*
X248925Y399258D01*
X249155Y399568D01*
X249308Y399930D01*
X249385Y400343D01*
Y400757D01*
X249308Y401170D01*
X249155Y401532D01*
X248925Y401842D01*
X248657Y402048D01*
X248350Y402100D01*
X248043Y402048D01*
X247775Y401842D01*
X247545Y401532D01*
X247392Y401170D01*
X247315Y400757D01*
Y400343D01*
X247392Y399930D01*
X247545Y399568D01*
X247775Y399258D01*
X248043Y399052D01*
X248350Y399000D01*
G01X248043Y399827D02*
X247583Y399000D01*
G01X244790D02*
Y402100D01*
X246208Y399878D01*
X244292D01*
G01X245900Y434645D02*
X265533D01*
G01X247581Y439548D02*
X248539Y436448D01*
X249497Y439548D01*
G01X249152Y438463D02*
X247926D01*
G01X251639Y439548D02*
Y436448D01*
X251179Y437068D01*
G01Y439548D02*
X252099D01*
G01X259900Y47400D02*
X266100D01*
Y50600D01*
X259900D01*
Y47400D01*
G01X266900D02*
X273100D01*
Y50600D01*
X266900D01*
Y47400D01*
G01X273100Y54600D02*
X266900D01*
Y51400D01*
X273100D01*
Y54600D01*
G01X259900Y51400D02*
X266100D01*
Y54600D01*
X259900D01*
Y51400D01*
G01X273100Y58600D02*
X266900D01*
Y55400D01*
X273100D01*
Y58600D01*
G01X285483Y93500D02*
X288017D01*
Y98500D01*
X285483D01*
G01X286497Y96083D02*
X288017D01*
G01X280383Y93500D02*
X282917D01*
Y98500D01*
X280383D01*
G01X281397Y96083D02*
X282917D01*
G01X277817Y93500D02*
Y98500D01*
X276297D01*
X275790Y98250D01*
X275410Y97667D01*
X275283Y97000D01*
X275410Y96333D01*
X275727Y95833D01*
X276297Y95583D01*
X277817D01*
G01X272717Y93500D02*
Y98500D01*
X271133D01*
X270627Y98250D01*
X270310Y97917D01*
X270183Y97250D01*
X270310Y96583D01*
X270690Y96167D01*
X271133Y95917D01*
X272717D01*
G01X271133D02*
X270183Y93500D01*
G01X266350D02*
X266857Y93583D01*
X267300Y93917D01*
X267680Y94417D01*
X267933Y95000D01*
X268060Y95667D01*
Y96333D01*
X267933Y97000D01*
X267680Y97583D01*
X267300Y98083D01*
X266857Y98417D01*
X266350Y98500D01*
X265843Y98417D01*
X265400Y98083D01*
X265020Y97583D01*
X264767Y97000D01*
X264640Y96333D01*
Y95667D01*
X264767Y95000D01*
X265020Y94417D01*
X265400Y93917D01*
X265843Y93583D01*
X266350Y93500D01*
G01X262897D02*
Y98500D01*
X261250Y94333D01*
X259603Y98500D01*
Y93500D01*
G01X267012Y103103D02*
X273212D01*
Y106303D01*
X267012D01*
Y103103D01*
G01Y106626D02*
X273212D01*
Y109826D01*
X267012D01*
Y106626D01*
G01X261946Y117926D02*
Y124126D01*
X258746D01*
Y117926D01*
X261946D01*
G01X273110Y118966D02*
X266910D01*
Y115766D01*
X273110D01*
Y118966D01*
G01X264270Y133969D02*
X268870D01*
G01X264270Y129469D02*
X268870D01*
G01X268770D02*
X268870D01*
Y139469D01*
G01X264270D02*
Y129469D01*
G01Y134969D02*
X268870D01*
G01X258600Y139470D02*
Y133270D01*
X261800D01*
Y139470D01*
X258600D01*
G01X269712Y156963D02*
Y152363D01*
G01Y152463D02*
Y152363D01*
X279712D01*
G01X264270Y139469D02*
X268870D01*
G01X274611Y146385D02*
X270011D01*
G01X274611Y150885D02*
X270011D01*
G01X274611Y140885D02*
X270011D01*
G01X270111Y150885D02*
X270011D01*
Y140885D01*
G01X274611Y145385D02*
X270011D01*
G01X260263Y148922D02*
Y142722D01*
X263463D01*
Y148922D01*
X260263D01*
G01X267466Y142650D02*
Y148850D01*
X264266D01*
Y142650D01*
X267466D01*
G01X279712Y156963D02*
X269712D01*
G01X267297Y164030D02*
Y157830D01*
X270497D01*
Y164030D01*
X267297D01*
G01X262297D02*
Y157830D01*
X265497D01*
Y164030D01*
X262297D01*
G01X268000Y168200D02*
Y172800D01*
G01X278000Y172700D02*
Y172800D01*
X268000D01*
G01Y168200D02*
X278000D01*
G01X280100Y226800D02*
X269900D01*
Y222200D01*
X280100D01*
Y226800D01*
G01X269870Y221029D02*
Y214829D01*
X273070D01*
Y221029D01*
X269870D01*
G01X263400Y241100D02*
Y247300D01*
X260200D01*
Y241100D01*
X263400D01*
G01X274357Y252504D02*
X269757D01*
G01X269857Y262504D02*
X269757D01*
Y252504D01*
G01X274357Y258004D02*
X269757D01*
G01X274357Y262504D02*
X269757D01*
G01X274357Y257004D02*
X269757D01*
G01X263400Y282200D02*
Y288400D01*
X260200D01*
Y282200D01*
X263400D01*
G01X270618Y357570D02*
X337547D01*
Y333948D01*
X270618D01*
Y357570D01*
G01X267900Y374200D02*
Y364000D01*
X272500D01*
Y374200D01*
X267900D01*
G01X265700Y382500D02*
X271900D01*
Y385700D01*
X265700D01*
Y382500D01*
G01X267000Y415950D02*
Y422150D01*
X263800D01*
Y415950D01*
X267000D01*
G01X263000D02*
Y422150D01*
X259800D01*
Y415950D01*
X263000D01*
G01X268450Y434645D02*
X292400D01*
G01X265039Y439548D02*
X264732Y439496D01*
X264464Y439290D01*
X264234Y438980D01*
X264081Y438618D01*
X264004Y438205D01*
Y437791D01*
X264081Y437378D01*
X264234Y437016D01*
X264464Y436706D01*
X264732Y436500D01*
X265039Y436448D01*
X265346Y436500D01*
X265614Y436706D01*
X265844Y437016D01*
X265997Y437378D01*
X266074Y437791D01*
Y438205D01*
X265997Y438618D01*
X265844Y438980D01*
X265614Y439290D01*
X265346Y439496D01*
X265039Y439548D01*
G01X267181D02*
X268139Y436448D01*
X269097Y439548D01*
G01X268752Y438463D02*
X267526D01*
G01X271239Y439548D02*
Y436448D01*
X270779Y437068D01*
G01Y439548D02*
X271699D01*
G01X274799D02*
Y436448D01*
X273381Y438670D01*
X275297D01*
G01X279293Y-670269D02*
X279893Y-669469D01*
X280593Y-669069D01*
X281393Y-668936D01*
X282393Y-669203D01*
X283093Y-669869D01*
X283293Y-670669D01*
X283193Y-671470D01*
X282793Y-672136D01*
X280793Y-673469D01*
X279893Y-674403D01*
X279293Y-675736D01*
X279093Y-676936D01*
X283293D01*
G01X289193Y-668936D02*
X288393Y-669203D01*
X287793Y-669869D01*
X287393Y-670669D01*
X287093Y-671736D01*
X286993Y-672936D01*
X287093Y-674136D01*
X287393Y-675203D01*
X287793Y-676003D01*
X288393Y-676669D01*
X289193Y-676936D01*
X289993Y-676669D01*
X290593Y-676003D01*
X290993Y-675203D01*
X291293Y-674136D01*
X291393Y-672936D01*
X291293Y-671736D01*
X290993Y-670669D01*
X290593Y-669869D01*
X289993Y-669203D01*
X289193Y-668936D01*
G01X295293Y-670269D02*
X295893Y-669469D01*
X296593Y-669069D01*
X297393Y-668936D01*
X298393Y-669203D01*
X299093Y-669869D01*
X299293Y-670669D01*
X299193Y-671470D01*
X298793Y-672136D01*
X296793Y-673469D01*
X295893Y-674403D01*
X295293Y-675736D01*
X295093Y-676936D01*
X299293D01*
G01X303293Y-670269D02*
X303893Y-669469D01*
X304593Y-669069D01*
X305393Y-668936D01*
X306393Y-669203D01*
X307093Y-669869D01*
X307293Y-670669D01*
X307193Y-671470D01*
X306793Y-672136D01*
X304793Y-673469D01*
X303893Y-674403D01*
X303293Y-675736D01*
X303093Y-676936D01*
X307293D01*
G01X311393Y-677203D02*
X314993Y-668936D01*
G01X321193Y-676936D02*
Y-668936D01*
X319993Y-670536D01*
G01Y-676936D02*
X322393D01*
G01X327293Y-670269D02*
X327893Y-669469D01*
X328593Y-669069D01*
X329393Y-668936D01*
X330393Y-669203D01*
X331093Y-669869D01*
X331293Y-670669D01*
X331193Y-671470D01*
X330793Y-672136D01*
X328793Y-673469D01*
X327893Y-674403D01*
X327293Y-675736D01*
X327093Y-676936D01*
X331293D01*
G01X335393Y-677203D02*
X338993Y-668936D01*
G01X345193D02*
X344393Y-669203D01*
X343793Y-669869D01*
X343393Y-670669D01*
X343093Y-671736D01*
X342993Y-672936D01*
X343093Y-674136D01*
X343393Y-675203D01*
X343793Y-676003D01*
X344393Y-676669D01*
X345193Y-676936D01*
X345993Y-676669D01*
X346593Y-676003D01*
X346993Y-675203D01*
X347293Y-674136D01*
X347393Y-672936D01*
X347293Y-671736D01*
X346993Y-670669D01*
X346593Y-669869D01*
X345993Y-669203D01*
X345193Y-668936D01*
G01X351493Y-676003D02*
X352193Y-676669D01*
X352993Y-676936D01*
X353793Y-676669D01*
X354493Y-675870D01*
X354993Y-674669D01*
X355193Y-673469D01*
Y-672003D01*
X354993Y-670803D01*
X354493Y-669736D01*
X353893Y-669203D01*
X353193Y-668936D01*
X352393Y-669203D01*
X351793Y-669736D01*
X351393Y-670536D01*
X351193Y-671603D01*
X351393Y-672536D01*
X351893Y-673469D01*
X352493Y-674003D01*
X353193Y-674136D01*
X353993Y-673870D01*
X354593Y-673203D01*
X355193Y-672003D01*
G01X278993Y-651936D02*
Y-643936D01*
X280993D01*
X281793Y-644336D01*
X282393Y-644869D01*
X282893Y-645669D01*
X283293Y-646603D01*
X283393Y-647936D01*
X283293Y-649269D01*
X282893Y-650203D01*
X282393Y-651003D01*
X281793Y-651536D01*
X280993Y-651936D01*
X278993D01*
G01X286693D02*
X289193Y-643936D01*
X291693Y-651936D01*
G01X290793Y-649136D02*
X287593D01*
G01X297193Y-643936D02*
X296393Y-644203D01*
X295793Y-644869D01*
X295393Y-645669D01*
X295093Y-646736D01*
X294993Y-647936D01*
X295093Y-649136D01*
X295393Y-650203D01*
X295793Y-651003D01*
X296393Y-651669D01*
X297193Y-651936D01*
X297993Y-651669D01*
X298593Y-651003D01*
X298993Y-650203D01*
X299293Y-649136D01*
X299393Y-647936D01*
X299293Y-646736D01*
X298993Y-645669D01*
X298593Y-644869D01*
X297993Y-644203D01*
X297193Y-643936D01*
G01X303293Y-651936D02*
Y-643936D01*
X307093D01*
G01X305693Y-647803D02*
X303293D01*
G01X313193Y-643936D02*
X312393Y-644203D01*
X311793Y-644869D01*
X311393Y-645669D01*
X311093Y-646736D01*
X310993Y-647936D01*
X311093Y-649136D01*
X311393Y-650203D01*
X311793Y-651003D01*
X312393Y-651669D01*
X313193Y-651936D01*
X313993Y-651669D01*
X314593Y-651003D01*
X314993Y-650203D01*
X315293Y-649136D01*
X315393Y-647936D01*
X315293Y-646736D01*
X314993Y-645669D01*
X314593Y-644869D01*
X313993Y-644203D01*
X313193Y-643936D01*
G01X321193D02*
Y-651936D01*
G01X318893Y-643936D02*
X323493D01*
G01X326593Y-651936D02*
Y-643936D01*
X329193Y-650603D01*
X331793Y-643936D01*
Y-651936D01*
G01X334993D02*
Y-643936D01*
X336993D01*
X337793Y-644336D01*
X338393Y-644869D01*
X338893Y-645669D01*
X339293Y-646603D01*
X339393Y-647936D01*
X339293Y-649269D01*
X338893Y-650203D01*
X338393Y-651003D01*
X337793Y-651536D01*
X336993Y-651936D01*
X334993D01*
G01X347393Y-644603D02*
X346793Y-644203D01*
X346093Y-643936D01*
X345293D01*
X344393Y-644336D01*
X343693Y-645003D01*
X343193Y-645803D01*
X342793Y-647136D01*
X342693Y-648336D01*
X342893Y-649536D01*
X343193Y-650336D01*
X343793Y-651136D01*
X344493Y-651669D01*
X345193Y-651936D01*
X345893D01*
X346593Y-651669D01*
X347193Y-651269D01*
X347693Y-650736D01*
G01X350993Y-651936D02*
Y-643936D01*
X352993D01*
X353793Y-644336D01*
X354393Y-644869D01*
X354893Y-645669D01*
X355293Y-646603D01*
X355393Y-647936D01*
X355293Y-649269D01*
X354893Y-650203D01*
X354393Y-651003D01*
X353793Y-651536D01*
X352993Y-651936D01*
X350993D01*
G01X361193Y-643936D02*
X360393Y-644203D01*
X359793Y-644869D01*
X359393Y-645669D01*
X359093Y-646736D01*
X358993Y-647936D01*
X359093Y-649136D01*
X359393Y-650203D01*
X359793Y-651003D01*
X360393Y-651669D01*
X361193Y-651936D01*
X361993Y-651669D01*
X362593Y-651003D01*
X362993Y-650203D01*
X363293Y-649136D01*
X363393Y-647936D01*
X363293Y-646736D01*
X362993Y-645669D01*
X362593Y-644869D01*
X361993Y-644203D01*
X361193Y-643936D01*
G01X279400Y80600D02*
Y74400D01*
X282600D01*
Y80600D01*
X279400D01*
G01X275400D02*
Y74400D01*
X278600D01*
Y80600D01*
X275400D01*
G01X283400D02*
Y74400D01*
X286600D01*
Y80600D01*
X283400D01*
G01X282902Y118991D02*
X276702D01*
Y115791D01*
X282902D01*
Y118991D01*
G01X272482Y119800D02*
X278682D01*
Y123000D01*
X272482D01*
Y119800D01*
G01X275100Y135100D02*
X285300D01*
Y139700D01*
X275100D01*
Y135100D01*
G01X280200D02*
Y139700D01*
G01X275431Y150985D02*
Y140785D01*
X280031D01*
Y150985D01*
X275431D01*
G01Y145885D02*
X280031D01*
G01X274212Y156963D02*
Y152363D01*
G01X279712Y156963D02*
Y152363D01*
G01X275212Y156963D02*
Y152363D01*
G01X274611Y140885D02*
Y150885D01*
G01X288052Y143639D02*
Y149839D01*
X284852D01*
Y143639D01*
X288052D01*
G01X284040D02*
Y149839D01*
X280840D01*
Y143639D01*
X284040D01*
G01X283300Y157900D02*
Y168100D01*
X278700D01*
Y157900D01*
X283300D01*
G01Y163000D02*
X278700D01*
G01X290144Y167402D02*
X283944D01*
Y164202D01*
X290144D01*
Y167402D01*
G01X274400Y167100D02*
Y160900D01*
X277600D01*
Y167100D01*
X274400D01*
G01X273500Y168200D02*
Y172800D01*
G01X278000Y168200D02*
Y172800D01*
G01X272500Y168200D02*
Y172800D01*
G01X285230Y177235D02*
X279030D01*
Y174035D01*
X285230D01*
Y177235D01*
G01X277268Y188558D02*
Y182358D01*
X280468D01*
Y188558D01*
X277268D01*
G01X284507Y182358D02*
Y188558D01*
X281307D01*
Y182358D01*
X284507D01*
G01X283840Y193159D02*
Y199359D01*
X280640D01*
Y193159D01*
X283840D01*
G01X292537Y189514D02*
X286337D01*
Y186314D01*
X292537D01*
Y189514D01*
G01X282764Y211111D02*
X276564D01*
Y207911D01*
X282764D01*
Y211111D01*
G01X280592Y206375D02*
Y200175D01*
X283792D01*
Y206375D01*
X280592D01*
G01X282764Y215130D02*
X276564D01*
Y211930D01*
X282764D01*
Y215130D01*
G01X275000Y226800D02*
Y222200D01*
G01X281178Y223551D02*
X285778D01*
G01X285678D02*
X285778D01*
Y233551D01*
G01X281178D02*
Y223551D01*
G01X279514Y216330D02*
Y220930D01*
G01X284014Y216330D02*
Y220930D01*
G01X274014Y216330D02*
Y220930D01*
G01X284014Y220830D02*
Y220930D01*
X274014D01*
G01Y216330D02*
X284014D01*
G01X278514D02*
Y220930D01*
G01X285011Y221209D02*
Y215009D01*
X288211D01*
Y221209D01*
X285011D01*
G01X281178Y228051D02*
X285778D01*
G01X281178Y233551D02*
X285778D01*
G01X281178Y229051D02*
X285778D01*
G01X285179Y236424D02*
Y242624D01*
X281979D01*
Y236424D01*
X285179D01*
G01X274357Y252504D02*
Y262504D01*
G01X280453Y252504D02*
X275853D01*
G01X275953Y262504D02*
X275853D01*
Y252504D01*
G01X280453D02*
Y262504D01*
G01X286290Y252505D02*
X281690D01*
G01X281790Y262505D02*
X281690D01*
Y252505D01*
G01X286290D02*
Y262505D01*
G01X281783Y250252D02*
Y244052D01*
X284983D01*
Y250252D01*
X281783D01*
G01X280453Y258004D02*
X275853D01*
G01X280453Y262504D02*
X275853D01*
G01X280453Y257004D02*
X275853D01*
G01X286290Y258005D02*
X281690D01*
G01X286290Y262505D02*
X281690D01*
G01X286290Y257005D02*
X281690D01*
G01X287511Y270822D02*
Y277022D01*
X284311D01*
Y270822D01*
X287511D01*
G01X283489D02*
Y277022D01*
X280289D01*
Y270822D01*
X283489D01*
G01Y280552D02*
Y286752D01*
X280289D01*
Y280552D01*
X283489D01*
G01X287511D02*
Y286752D01*
X284311D01*
Y280552D01*
X287511D01*
G01X298418Y-624819D02*
Y-618519D01*
X301394D01*
G01X300298Y-621564D02*
X298418D01*
G01X306206Y-618519D02*
X305579Y-618729D01*
X305109Y-619254D01*
X304796Y-619884D01*
X304561Y-620724D01*
X304483Y-621669D01*
X304561Y-622614D01*
X304796Y-623454D01*
X305109Y-624084D01*
X305579Y-624609D01*
X306206Y-624819D01*
X306833Y-624609D01*
X307303Y-624084D01*
X307616Y-623454D01*
X307851Y-622614D01*
X307929Y-621669D01*
X307851Y-620724D01*
X307616Y-619884D01*
X307303Y-619254D01*
X306833Y-618729D01*
X306206Y-618519D01*
G01X312506D02*
Y-624819D01*
G01X310704Y-618519D02*
X314308D01*
G01X316456Y-626919D02*
X321156D01*
G01X323069Y-624819D02*
Y-618519D01*
X325106Y-623769D01*
X327143Y-618519D01*
Y-624819D01*
G01X332816D02*
Y-620619D01*
G01Y-621354D02*
X332503Y-620934D01*
X332033Y-620724D01*
X331484Y-620619D01*
X330936Y-620829D01*
X330466Y-621249D01*
X330153Y-621879D01*
X329996Y-622719D01*
X330153Y-623559D01*
X330466Y-624189D01*
X330936Y-624609D01*
X331484Y-624819D01*
X332033Y-624714D01*
X332503Y-624399D01*
X332816Y-623979D01*
G01X336374Y-624819D02*
Y-620619D01*
G01Y-621669D02*
X336688Y-621144D01*
X337158Y-620724D01*
X337784Y-620619D01*
X338333Y-620724D01*
X338803Y-621144D01*
X339038Y-621879D01*
Y-624819D01*
G01X345416D02*
Y-620619D01*
G01Y-621354D02*
X345103Y-620934D01*
X344633Y-620724D01*
X344084Y-620619D01*
X343536Y-620829D01*
X343066Y-621249D01*
X342753Y-621879D01*
X342596Y-622719D01*
X342753Y-623559D01*
X343066Y-624189D01*
X343536Y-624609D01*
X344084Y-624819D01*
X344633Y-624714D01*
X345103Y-624399D01*
X345416Y-623979D01*
G01X349209Y-626394D02*
X349758Y-626814D01*
X350384Y-626919D01*
X350933Y-626814D01*
X351403Y-626289D01*
X351716Y-625554D01*
Y-620619D01*
G01Y-621459D02*
X351403Y-621039D01*
X350933Y-620724D01*
X350384Y-620619D01*
X349758Y-620829D01*
X349366Y-621249D01*
X349053Y-621984D01*
X348896Y-622719D01*
X348974Y-623349D01*
X349288Y-624084D01*
X349758Y-624609D01*
X350384Y-624819D01*
X350854Y-624714D01*
X351403Y-624294D01*
X351716Y-623874D01*
G01X355431Y-621984D02*
X357938D01*
X357703Y-621249D01*
X357311Y-620829D01*
X356763Y-620619D01*
X356214Y-620724D01*
X355744Y-621039D01*
X355431Y-621774D01*
X355274Y-622404D01*
Y-623034D01*
X355431Y-623664D01*
X355823Y-624294D01*
X356293Y-624714D01*
X356841Y-624819D01*
X357389Y-624609D01*
X357938Y-623979D01*
G01X360556Y-624819D02*
Y-620619D01*
G01Y-621774D02*
X360791Y-621249D01*
X361183Y-620829D01*
X361731Y-620619D01*
X362279Y-620829D01*
X362671Y-621249D01*
X362906Y-621774D01*
Y-624819D01*
G01Y-621774D02*
X363141Y-621249D01*
X363533Y-620829D01*
X364081Y-620619D01*
X364629Y-620829D01*
X365021Y-621249D01*
X365256Y-621879D01*
Y-624819D01*
G01X368031Y-621984D02*
X370538D01*
X370303Y-621249D01*
X369911Y-620829D01*
X369363Y-620619D01*
X368814Y-620724D01*
X368344Y-621039D01*
X368031Y-621774D01*
X367874Y-622404D01*
Y-623034D01*
X368031Y-623664D01*
X368423Y-624294D01*
X368893Y-624714D01*
X369441Y-624819D01*
X369989Y-624609D01*
X370538Y-623979D01*
G01X374174Y-624819D02*
Y-620619D01*
G01Y-621669D02*
X374488Y-621144D01*
X374958Y-620724D01*
X375584Y-620619D01*
X376133Y-620724D01*
X376603Y-621144D01*
X376838Y-621879D01*
Y-624819D01*
G01X381806Y-618519D02*
Y-624819D01*
G01X380709Y-620619D02*
X382903D01*
G01X385756Y-626919D02*
X390456D01*
G01X395033Y-621459D02*
X395346Y-621144D01*
X395581Y-620619D01*
X395738Y-619884D01*
X395581Y-619254D01*
X395268Y-618834D01*
X394719Y-618519D01*
X392604D01*
Y-624819D01*
X395189D01*
X395738Y-624399D01*
X396051Y-623769D01*
X396208Y-623034D01*
X396051Y-622299D01*
X395581Y-621669D01*
X395033Y-621459D01*
X392604D01*
G01X398983Y-624819D02*
Y-618519D01*
X400549D01*
X401176Y-618834D01*
X401646Y-619254D01*
X402038Y-619884D01*
X402351Y-620619D01*
X402429Y-621669D01*
X402351Y-622719D01*
X402038Y-623454D01*
X401646Y-624084D01*
X401176Y-624504D01*
X400549Y-624819D01*
X398983D01*
G01X305935Y113031D02*
X300806D01*
X298242Y110467D01*
X295678Y113031D01*
X290549D01*
Y100827D01*
X305935D01*
Y113031D01*
G01X293900Y96000D02*
X300100D01*
Y99200D01*
X293900D01*
Y96000D01*
G01X294300Y114700D02*
X300500D01*
Y117900D01*
X294300D01*
Y114700D01*
G01X289288Y135570D02*
X299488D01*
Y140170D01*
X289288D01*
Y135570D01*
G01X294388D02*
Y140170D01*
G01X303536Y136822D02*
Y143022D01*
X300336D01*
Y136822D01*
X303536D01*
G01X291600Y130100D02*
X297800D01*
Y133300D01*
X291600D01*
Y130100D01*
G01X291400Y124900D02*
X297600D01*
Y128100D01*
X291400D01*
Y124900D01*
G01X300336Y150972D02*
Y144772D01*
X303536D01*
Y150972D01*
X300336D01*
G01X292087Y143639D02*
Y149839D01*
X288887D01*
Y143639D01*
X292087D01*
G01X305000Y183485D02*
X299982D01*
Y180285D01*
X306182D01*
Y182000D01*
G01Y187485D02*
X299982D01*
Y184285D01*
X305000D01*
G01X303107Y188360D02*
Y194560D01*
X299907D01*
Y188360D01*
X303107D01*
G01X296751Y204254D02*
X302951D01*
Y207454D01*
X296751D01*
Y204254D01*
G01X302457Y214962D02*
Y225162D01*
X297857D01*
Y214962D01*
X302457D01*
G01Y220062D02*
X297857D01*
G01X296828Y219064D02*
Y229264D01*
X292228D01*
Y219064D01*
X296828D01*
G01Y224164D02*
X292228D01*
G01X286802Y223498D02*
X291402D01*
G01X291302D02*
X291402D01*
Y233498D01*
G01X286802D02*
Y223498D01*
G01Y227998D02*
X291402D01*
G01X286802Y233498D02*
X291402D01*
G01X286802Y228998D02*
X291402D01*
G01X295757Y237817D02*
Y231617D01*
X298957D01*
Y237817D01*
X295757D01*
G01X295762Y364452D02*
Y370652D01*
X292562D01*
Y364452D01*
X295762D01*
G01X288251Y373648D02*
X300063D01*
Y386272D01*
X288251D01*
Y373648D01*
G01X294250Y387400D02*
X294557Y387452D01*
X294825Y387658D01*
X295055Y387968D01*
X295208Y388330D01*
X295285Y388743D01*
Y389157D01*
X295208Y389570D01*
X295055Y389932D01*
X294825Y390242D01*
X294557Y390448D01*
X294250Y390500D01*
X293943Y390448D01*
X293675Y390242D01*
X293445Y389932D01*
X293292Y389570D01*
X293215Y389157D01*
Y388743D01*
X293292Y388330D01*
X293445Y387968D01*
X293675Y387658D01*
X293943Y387452D01*
X294250Y387400D01*
G01X293943Y388227D02*
X293483Y387400D01*
G01X291227D02*
X291150Y388072D01*
X291035Y388640D01*
X290882Y389157D01*
X290690Y389725D01*
X290383Y390500D01*
X291917D01*
G01X294814Y394932D02*
X288614D01*
Y391732D01*
X294814D01*
Y394932D01*
G01X307350Y394952D02*
X301150D01*
Y391752D01*
X307350D01*
Y394952D01*
G01X288614Y395765D02*
X294814D01*
Y398965D01*
X288614D01*
Y395765D01*
G01X307350Y398982D02*
X301150D01*
Y395782D01*
X307350D01*
Y398982D01*
G01X294689Y439548D02*
X294382Y439496D01*
X294114Y439290D01*
X293884Y438980D01*
X293731Y438618D01*
X293654Y438205D01*
Y437791D01*
X293731Y437378D01*
X293884Y437016D01*
X294114Y436706D01*
X294382Y436500D01*
X294689Y436448D01*
X294996Y436500D01*
X295264Y436706D01*
X295494Y437016D01*
X295647Y437378D01*
X295724Y437791D01*
Y438205D01*
X295647Y438618D01*
X295494Y438980D01*
X295264Y439290D01*
X294996Y439496D01*
X294689Y439548D01*
G01X296831D02*
X297789Y436448D01*
X298747Y439548D01*
G01X298402Y438463D02*
X297176D01*
G01X300889Y439548D02*
Y436448D01*
X300429Y437068D01*
G01Y439548D02*
X301349D01*
G01X323178Y101200D02*
Y104300D01*
X321722D01*
G01X322258Y102802D02*
X323178D01*
G01X320117Y101200D02*
Y104300D01*
X319158D01*
X318852Y104145D01*
X318660Y103938D01*
X318583Y103525D01*
X318660Y103112D01*
X318890Y102853D01*
X319158Y102698D01*
X320117D01*
G01X319158D02*
X318583Y101200D01*
G01X317093Y104300D02*
Y102078D01*
X316940Y101613D01*
X316633Y101303D01*
X316250Y101200D01*
X315867Y101303D01*
X315560Y101613D01*
X315407Y102078D01*
Y104300D01*
G01X310943Y99550D02*
Y97328D01*
X310790Y96863D01*
X310483Y96553D01*
X310100Y96450D01*
X309717Y96553D01*
X309410Y96863D01*
X309257Y97328D01*
Y99550D01*
G01X307000Y96450D02*
Y99550D01*
X307460Y98930D01*
G01Y96450D02*
X306540D01*
G01X304552Y96812D02*
X304283Y96553D01*
X303977Y96450D01*
X303670Y96553D01*
X303402Y96863D01*
X303210Y97328D01*
X303133Y97793D01*
Y98362D01*
X303210Y98827D01*
X303402Y99240D01*
X303632Y99447D01*
X303900Y99550D01*
X304207Y99447D01*
X304437Y99240D01*
X304590Y98930D01*
X304667Y98517D01*
X304590Y98155D01*
X304398Y97793D01*
X304168Y97587D01*
X303900Y97535D01*
X303593Y97638D01*
X303363Y97897D01*
X303133Y98362D01*
G01X317500Y123600D02*
X311300D01*
Y120400D01*
X317500D01*
Y123600D01*
G01X312100Y113900D02*
Y120100D01*
X308900D01*
Y113900D01*
X312100D01*
G01X303400Y125600D02*
Y119400D01*
X306600D01*
Y125600D01*
X303400D01*
G01X315536Y136822D02*
Y143022D01*
X312336D01*
Y136822D01*
X315536D01*
G01X311536D02*
Y143022D01*
X308336D01*
Y136822D01*
X311536D01*
G01X319536D02*
Y143022D01*
X316336D01*
Y136822D01*
X319536D01*
G01X307536D02*
Y143022D01*
X304336D01*
Y136822D01*
X307536D01*
G01X315600Y128650D02*
Y134850D01*
X312400D01*
Y128650D01*
X315600D01*
G01X308100Y132890D02*
X301900D01*
Y129690D01*
X308100D01*
Y132890D01*
G01X311800Y128650D02*
Y134850D01*
X308600D01*
Y128650D01*
X311800D01*
G01X312336Y150972D02*
Y144772D01*
X315536D01*
Y150972D01*
X312336D01*
G01X316336D02*
Y144772D01*
X319536D01*
Y150972D01*
X316336D01*
G01X308336D02*
Y144772D01*
X311536D01*
Y150972D01*
X308336D01*
G01X304336D02*
Y144772D01*
X307536D01*
Y150972D01*
X304336D01*
G01X322509Y162978D02*
X316309D01*
Y159778D01*
X322509D01*
Y162978D01*
G01Y166978D02*
X316309D01*
Y163778D01*
X322509D01*
Y166978D01*
G01Y158978D02*
X316309D01*
Y155778D01*
X322509D01*
Y158978D01*
G01X316309Y171778D02*
X322509D01*
Y174978D01*
X316309D01*
Y171778D01*
G01Y175778D02*
X322509D01*
Y178978D01*
X316309D01*
Y175778D01*
G01Y167778D02*
X322509D01*
Y170978D01*
X316309D01*
Y167778D01*
G01X306182Y185500D02*
Y187485D01*
G01X318134Y189972D02*
X311934D01*
Y186772D01*
X318134D01*
Y189972D01*
G01X315379Y197044D02*
Y190844D01*
X318579D01*
Y197044D01*
X315379D01*
G01X307107Y188360D02*
Y194560D01*
X303907D01*
Y188360D01*
X307107D01*
G01X318716Y197850D02*
Y204050D01*
X315516D01*
Y197850D01*
X318716D01*
G01X304080Y199189D02*
X310280D01*
Y202389D01*
X304080D01*
Y199189D01*
G01X315511Y213109D02*
Y206909D01*
X318711D01*
Y213109D01*
X315511D01*
G01X316405Y217737D02*
X310205D01*
Y214537D01*
X316405D01*
Y217737D01*
G01X309700Y258700D02*
X315900D01*
Y261900D01*
X309700D01*
Y258700D01*
G01Y271300D02*
Y277000D01*
G01Y263600D02*
Y269300D01*
G01Y263600D02*
X318500D01*
G01X309700Y269300D02*
X311300Y270300D01*
X309700Y271300D01*
G01X318500Y277000D02*
X309700D01*
G01X334648Y348833D02*
X333901Y348208D01*
X333061Y347833D01*
X332315D01*
X331568Y348208D01*
X331008Y348833D01*
X330728Y349708D01*
X330915Y350583D01*
X331381Y351333D01*
X332221Y351833D01*
X333341Y352083D01*
X333995Y352583D01*
X334275Y353458D01*
X334088Y354333D01*
X333621Y354958D01*
X332968Y355333D01*
X332315D01*
X331661Y355083D01*
X331101Y354458D01*
G01X326868Y347583D02*
X323508Y355333D01*
G01X319835Y347833D02*
Y355333D01*
X315541Y347833D01*
Y355333D01*
G01X313100Y374600D02*
X306900D01*
Y371400D01*
X313100D01*
Y374600D01*
G01X310400Y367400D02*
X316600D01*
Y370600D01*
X310400D01*
Y367400D01*
G01X322600Y375950D02*
X322907Y376002D01*
X323175Y376208D01*
X323405Y376518D01*
X323558Y376880D01*
X323635Y377293D01*
Y377707D01*
X323558Y378120D01*
X323405Y378482D01*
X323175Y378792D01*
X322907Y378998D01*
X322600Y379050D01*
X322293Y378998D01*
X322025Y378792D01*
X321795Y378482D01*
X321642Y378120D01*
X321565Y377707D01*
Y377293D01*
X321642Y376880D01*
X321795Y376518D01*
X322025Y376208D01*
X322293Y376002D01*
X322600Y375950D01*
G01X322293Y376777D02*
X321833Y375950D01*
G01X319500D02*
Y379050D01*
X319960Y378430D01*
G01Y375950D02*
X319040D01*
G01X316400Y379050D02*
X316707Y378947D01*
X316937Y378688D01*
X317090Y378378D01*
X317205Y377965D01*
X317243Y377500D01*
X317205Y377035D01*
X317090Y376622D01*
X316937Y376312D01*
X316707Y376053D01*
X316400Y375950D01*
X316093Y376053D01*
X315863Y376312D01*
X315710Y376622D01*
X315595Y377035D01*
X315557Y377500D01*
X315595Y377965D01*
X315710Y378378D01*
X315863Y378688D01*
X316093Y378947D01*
X316400Y379050D01*
G01X302580Y376047D02*
X314392D01*
Y388671D01*
X302580D01*
Y376047D01*
G01X332275Y457374D02*
G03X351233Y409126I8367J-24561D01*
G01X324788Y103076D02*
X330988D01*
Y106276D01*
X324788D01*
Y103076D01*
G01Y107092D02*
X330988D01*
Y110292D01*
X324788D01*
Y107092D01*
G01X325000Y117950D02*
X335200D01*
Y122550D01*
X325000D01*
Y117950D01*
G01X330100D02*
Y122550D01*
G01X324788Y111107D02*
X330988D01*
Y114307D01*
X324788D01*
Y111107D01*
G01X328300Y123900D02*
Y134100D01*
X323700D01*
Y123900D01*
X328300D01*
G01Y129000D02*
X323700D01*
G01X319600Y128650D02*
Y134850D01*
X316400D01*
Y128650D01*
X319600D01*
G01X316434Y151777D02*
X322634D01*
Y154977D01*
X316434D01*
Y151777D01*
G01X323746Y148540D02*
X329946D01*
Y151740D01*
X323746D01*
Y148540D01*
G01X324330Y153811D02*
X330530D01*
Y157011D01*
X324330D01*
Y153811D01*
G01X330530Y161011D02*
X324330D01*
Y157811D01*
X330530D01*
Y161011D01*
G01X324330Y165811D02*
X330530D01*
Y169011D01*
X324330D01*
Y165811D01*
G01Y161811D02*
X330530D01*
Y165011D01*
X324330D01*
Y161811D01*
G01X330530Y185011D02*
X324330D01*
Y181811D01*
X330530D01*
Y185011D01*
G01Y181011D02*
X324330D01*
Y177811D01*
X330530D01*
Y181011D01*
G01X324330Y173811D02*
X330530D01*
Y177011D01*
X324330D01*
Y173811D01*
G01X323530Y185011D02*
X317330D01*
Y181811D01*
X323530D01*
Y185011D01*
G01X324330Y169811D02*
X330530D01*
Y173011D01*
X324330D01*
Y169811D01*
G01X321411Y194186D02*
X331611D01*
Y198786D01*
X321411D01*
Y194186D01*
G01X326511D02*
Y198786D01*
G01X330530Y189011D02*
X324330D01*
Y185811D01*
X330530D01*
Y189011D01*
G01Y193011D02*
X324330D01*
Y189811D01*
X330530D01*
Y193011D01*
G01X323202Y185820D02*
Y192020D01*
X320002D01*
Y185820D01*
X323202D01*
G01X320161Y202064D02*
X326361D01*
Y205264D01*
X320161D01*
Y202064D01*
G01X327960Y208688D02*
X334160D01*
Y211888D01*
X327960D01*
Y208688D01*
G01X320161Y206064D02*
X326361D01*
Y209264D01*
X320161D01*
Y206064D01*
G01X327960Y200688D02*
X334160D01*
Y203888D01*
X327960D01*
Y200688D01*
G01Y204688D02*
X334160D01*
Y207888D01*
X327960D01*
Y204688D01*
G01X328200Y236300D02*
Y226100D01*
X332800D01*
Y236300D01*
X328200D01*
G01X319700Y237600D02*
Y227400D01*
X324300D01*
Y237600D01*
X319700D01*
G01Y232500D02*
X324300D01*
G01X328200Y231200D02*
X332800D01*
G01X328100Y247500D02*
G03X334900Y242500I6035J1083D01*
G01X334800Y252700D02*
G03X328100Y247500I-585J-6163D01*
G01X329800Y255550D02*
X329700Y255750D01*
X329600Y255900D01*
X329500Y256000D01*
X329300Y256050D01*
X329150D01*
X328950Y256000D01*
X328800Y255800D01*
X328700Y255600D01*
Y254350D01*
G01X329800Y256050D02*
Y254350D01*
G01X327600Y256000D02*
X326700D01*
G01X327150Y256850D02*
Y254350D01*
X326450Y254400D01*
G01X324450Y255950D02*
X324600Y256000D01*
X324800Y256050D01*
X324950D01*
X325150Y256000D01*
X325250Y255950D01*
X325400Y255850D01*
X325500Y255750D01*
X325600Y255600D01*
X325650Y255500D01*
X325700Y255250D01*
Y255100D01*
X325650Y254900D01*
X325600Y254800D01*
X325500Y254650D01*
X325400Y254550D01*
X325250Y254450D01*
X325150Y254400D01*
X324900Y254350D01*
X324700D01*
X324450Y254450D01*
G01X322750Y256850D02*
Y254350D01*
X322050Y254400D01*
G01X323200Y256000D02*
X322300D01*
G01X342310Y266500D02*
G03I-8010J0D01*
G01X339500Y272500D02*
X328500Y261000D01*
G01X323600Y265257D02*
X321378D01*
X320913Y265410D01*
X320603Y265717D01*
X320500Y266100D01*
X320603Y266483D01*
X320913Y266790D01*
X321378Y266943D01*
X323600D01*
G01X320965Y268357D02*
X320707Y268587D01*
X320552Y268855D01*
X320500Y269200D01*
X320603Y269545D01*
X320810Y269813D01*
X321172Y270005D01*
X321585Y270043D01*
X321998Y269967D01*
X322257Y269775D01*
X322463Y269507D01*
X322515Y269238D01*
X322463Y268970D01*
X322257Y268625D01*
X323600Y268740D01*
Y269775D01*
G01X323083Y271572D02*
X323393Y271802D01*
X323548Y272070D01*
X323600Y272377D01*
X323497Y272760D01*
X323238Y273028D01*
X322928Y273105D01*
X322618Y273067D01*
X322360Y272913D01*
X321843Y272147D01*
X321482Y271802D01*
X320965Y271572D01*
X320500Y271495D01*
Y273105D01*
G01X318500Y263600D02*
Y277000D01*
G01X329392Y385035D02*
X335592D01*
Y388235D01*
X329392D01*
Y385035D01*
G01Y389101D02*
X335592D01*
Y392301D01*
X329392D01*
Y389101D01*
G01X317000Y393500D02*
X323000D01*
Y405500D01*
X317000D01*
Y393500D01*
G01X324000D02*
X330000D01*
Y405500D01*
X324000D01*
Y393500D01*
G01X339015Y110292D02*
X332815D01*
Y107092D01*
X339015D01*
Y110292D01*
G01Y106276D02*
X332815D01*
Y103076D01*
X339015D01*
Y106276D01*
G01Y114308D02*
X332815D01*
Y111108D01*
X339015D01*
Y114308D01*
G01X332725Y153311D02*
X338925D01*
Y156511D01*
X332725D01*
Y153311D01*
G01Y157311D02*
X338925D01*
Y160511D01*
X332725D01*
Y157311D01*
G01Y161311D02*
X338925D01*
Y164511D01*
X332725D01*
Y161311D01*
G01Y165311D02*
X338925D01*
Y168511D01*
X332725D01*
Y165311D01*
G01X332653Y169311D02*
X338853D01*
Y172511D01*
X332653D01*
Y169311D01*
G01X332725Y181326D02*
X338925D01*
Y184526D01*
X332725D01*
Y181326D01*
G01Y177311D02*
X338925D01*
Y180511D01*
X332725D01*
Y177311D01*
G01X332653Y173311D02*
X338853D01*
Y176511D01*
X332653D01*
Y173311D01*
G01X332725Y189361D02*
X338925D01*
Y192561D01*
X332725D01*
Y189361D01*
G01X338925Y188561D02*
X332725D01*
Y185361D01*
X338925D01*
Y188561D01*
G01X333800Y252700D02*
G02X340500Y247500I585J-6163D01*
G01D02*
G02X333700Y242500I-6035J1083D01*
G01X346650Y256450D02*
X346550Y256650D01*
X346450Y256750D01*
X346300Y256850D01*
X346100Y256900D01*
X345850Y256850D01*
X345600Y256600D01*
X345550Y256450D01*
Y256100D01*
X345600Y255950D01*
X345700Y255800D01*
X345800Y255700D01*
X345950Y255600D01*
X346150Y255450D01*
X346300Y255250D01*
X346400Y255150D01*
X346500Y255000D01*
X346600Y254700D01*
X346650Y254350D01*
X345450D01*
G01X344500Y256050D02*
Y254350D01*
G01Y255550D02*
X344400Y255750D01*
X344300Y255900D01*
X344200Y256000D01*
X344000Y256050D01*
X343850D01*
X343650Y256000D01*
X343500Y255800D01*
X343400Y255600D01*
Y254350D01*
G01X341200Y256900D02*
Y254350D01*
G01X342460Y255100D02*
G03I-710J0D01*
G01X341200Y255550D02*
X341300Y255650D01*
X341450Y255750D01*
X341600Y255800D01*
X341850D01*
X342050Y255750D01*
X342200Y255650D01*
X342350Y255500D01*
X342400Y255400D01*
X342450Y255250D01*
Y255050D01*
X342400Y254800D01*
X342300Y254650D01*
X342200Y254550D01*
X342050Y254450D01*
X341900Y254400D01*
X341700D01*
X341450Y254450D01*
X341300Y254550D01*
X341200Y254650D01*
G01X338850Y256950D02*
Y254350D01*
G01X337350Y256050D02*
X336650Y254350D01*
X335950Y256050D01*
G01X334450Y256950D02*
Y254350D01*
G01X331550Y256100D02*
Y254350D01*
G01Y257350D02*
X331650Y257250D01*
Y257150D01*
X331550Y257050D01*
X331450Y257150D01*
Y257250D01*
X331550Y257350D01*
G01X367693Y-679936D02*
Y-671936D01*
X366493Y-673536D01*
G01Y-679936D02*
X368893D01*
G01X373793Y-676603D02*
X374493Y-675669D01*
X375093Y-675136D01*
X375893Y-674869D01*
X376593Y-675136D01*
X377093Y-675669D01*
X377493Y-676469D01*
X377593Y-677403D01*
X377493Y-678203D01*
X377093Y-679003D01*
X376493Y-679669D01*
X375793Y-679936D01*
X374993Y-679669D01*
X374293Y-678870D01*
X373893Y-677669D01*
X373793Y-676336D01*
X373993Y-674603D01*
X374293Y-673669D01*
X374793Y-672736D01*
X375493Y-672069D01*
X376193Y-671936D01*
X376893Y-672203D01*
X377393Y-672869D01*
G01X383693Y-680203D02*
X383493Y-680069D01*
Y-679803D01*
X383693Y-679669D01*
X383893Y-679803D01*
Y-680069D01*
X383693Y-680203D01*
G01X389793Y-676603D02*
X390493Y-675669D01*
X391093Y-675136D01*
X391893Y-674869D01*
X392593Y-675136D01*
X393093Y-675669D01*
X393493Y-676469D01*
X393593Y-677403D01*
X393493Y-678203D01*
X393093Y-679003D01*
X392493Y-679669D01*
X391793Y-679936D01*
X390993Y-679669D01*
X390293Y-678870D01*
X389893Y-677669D01*
X389793Y-676336D01*
X389993Y-674603D01*
X390293Y-673669D01*
X390793Y-672736D01*
X391493Y-672069D01*
X392193Y-671936D01*
X392893Y-672203D01*
X393393Y-672869D01*
G01X374401Y-439163D02*
X369304D01*
Y-448763D01*
X385904D01*
Y-439163D01*
G01X365620Y-213617D02*
X365310Y-213425D01*
X365103Y-213195D01*
X365000Y-212927D01*
X365103Y-212620D01*
X365310Y-212390D01*
X365620Y-212160D01*
X366033Y-212083D01*
X368100D01*
G01X365000Y-209750D02*
X368100D01*
X367480Y-210210D01*
G01X365000D02*
Y-209290D01*
G01Y-206650D02*
X368100D01*
X367480Y-207110D01*
G01X365000D02*
Y-206190D01*
G01X369364Y-214941D02*
X374508D01*
G01X381075D02*
X385964D01*
Y-205341D01*
X369364D01*
Y-214941D01*
G01X395470Y-465225D02*
X390392D01*
Y-474825D01*
X406992D01*
Y-465225D01*
G01X382620Y-467617D02*
X382310Y-467425D01*
X382103Y-467195D01*
X382000Y-466927D01*
X382103Y-466620D01*
X382310Y-466390D01*
X382620Y-466160D01*
X383033Y-466083D01*
X385100D01*
G01X384583Y-464478D02*
X384893Y-464248D01*
X385048Y-463980D01*
X385100Y-463673D01*
X384997Y-463290D01*
X384738Y-463022D01*
X384428Y-462945D01*
X384118Y-462983D01*
X383860Y-463137D01*
X383343Y-463903D01*
X382982Y-464248D01*
X382465Y-464478D01*
X382000Y-464555D01*
Y-462945D01*
G01X382362Y-461302D02*
X382103Y-461033D01*
X382000Y-460727D01*
X382103Y-460420D01*
X382413Y-460152D01*
X382878Y-459960D01*
X383343Y-459883D01*
X383912D01*
X384377Y-459960D01*
X384790Y-460152D01*
X384997Y-460382D01*
X385100Y-460650D01*
X384997Y-460957D01*
X384790Y-461187D01*
X384480Y-461340D01*
X384067Y-461417D01*
X383705Y-461340D01*
X383343Y-461148D01*
X383137Y-460918D01*
X383085Y-460650D01*
X383188Y-460343D01*
X383447Y-460113D01*
X383912Y-459883D01*
G01X385904Y-439163D02*
X380859D01*
G01X386620Y-119617D02*
X386310Y-119425D01*
X386103Y-119195D01*
X386000Y-118927D01*
X386103Y-118620D01*
X386310Y-118390D01*
X386620Y-118160D01*
X387033Y-118083D01*
X389100D01*
G01X388583Y-116478D02*
X388893Y-116248D01*
X389048Y-115980D01*
X389100Y-115673D01*
X388997Y-115290D01*
X388738Y-115022D01*
X388428Y-114945D01*
X388118Y-114983D01*
X387860Y-115137D01*
X387343Y-115903D01*
X386982Y-116248D01*
X386465Y-116478D01*
X386000Y-116555D01*
Y-114945D01*
G01Y-112650D02*
X386052Y-112382D01*
X386207Y-112075D01*
X386465Y-111883D01*
X386827Y-111807D01*
X387188Y-111883D01*
X387498Y-112113D01*
X387653Y-112458D01*
Y-112842D01*
X387757Y-113072D01*
X388015Y-113263D01*
X388377Y-113340D01*
X388738Y-113225D01*
X388997Y-112957D01*
X389100Y-112650D01*
X388997Y-112343D01*
X388738Y-112075D01*
X388377Y-111960D01*
X388015Y-112037D01*
X387757Y-112228D01*
X387653Y-112458D01*
Y-112842D01*
X387498Y-113187D01*
X387188Y-113417D01*
X386827Y-113493D01*
X386465Y-113417D01*
X386207Y-113225D01*
X386052Y-112918D01*
X386000Y-112650D01*
G01X390480Y-120003D02*
X395506D01*
G01X402361D02*
X407080D01*
Y-110403D01*
X390480D01*
Y-120003D01*
G01X386620Y-74617D02*
X386310Y-74425D01*
X386103Y-74195D01*
X386000Y-73927D01*
X386103Y-73620D01*
X386310Y-73390D01*
X386620Y-73160D01*
X387033Y-73083D01*
X389100D01*
G01X388583Y-71478D02*
X388893Y-71248D01*
X389048Y-70980D01*
X389100Y-70673D01*
X388997Y-70290D01*
X388738Y-70022D01*
X388428Y-69945D01*
X388118Y-69983D01*
X387860Y-70137D01*
X387343Y-70903D01*
X386982Y-71248D01*
X386465Y-71478D01*
X386000Y-71555D01*
Y-69945D01*
G01Y-67727D02*
X386672Y-67650D01*
X387240Y-67535D01*
X387757Y-67382D01*
X388325Y-67190D01*
X389100Y-66883D01*
Y-68417D01*
G01X396917Y-66072D02*
X390450D01*
Y-75672D01*
X407050D01*
Y-66072D01*
G01X385620Y210383D02*
X385310Y210575D01*
X385103Y210805D01*
X385000Y211073D01*
X385103Y211380D01*
X385310Y211610D01*
X385620Y211840D01*
X386033Y211917D01*
X388100D01*
G01X387583Y213522D02*
X387893Y213752D01*
X388048Y214020D01*
X388100Y214327D01*
X387997Y214710D01*
X387738Y214978D01*
X387428Y215055D01*
X387118Y215017D01*
X386860Y214863D01*
X386343Y214097D01*
X385982Y213752D01*
X385465Y213522D01*
X385000Y213445D01*
Y215055D01*
G01Y217810D02*
X388100D01*
X385878Y216392D01*
Y218308D01*
G01X390450Y209388D02*
X396913D01*
G01X400593D02*
X407050D01*
Y218988D01*
X390450D01*
Y209388D01*
G01X403620Y-493617D02*
X403310Y-493425D01*
X403103Y-493195D01*
X403000Y-492927D01*
X403103Y-492620D01*
X403310Y-492390D01*
X403620Y-492160D01*
X404033Y-492083D01*
X406100D01*
G01X403620Y-490593D02*
X403258Y-490363D01*
X403052Y-490057D01*
X403000Y-489712D01*
X403052Y-489405D01*
X403310Y-489098D01*
X403620Y-488907D01*
X403930Y-488868D01*
X404292Y-488945D01*
X404550Y-489213D01*
X404653Y-489482D01*
Y-489827D01*
G01Y-489482D02*
X404808Y-489252D01*
X405067Y-489060D01*
X405377Y-488983D01*
X405687Y-489060D01*
X405945Y-489252D01*
X406100Y-489597D01*
X406048Y-489942D01*
X405842Y-490287D01*
G01X406100Y-486650D02*
X405997Y-486957D01*
X405738Y-487187D01*
X405428Y-487340D01*
X405015Y-487455D01*
X404550Y-487493D01*
X404085Y-487455D01*
X403672Y-487340D01*
X403362Y-487187D01*
X403103Y-486957D01*
X403000Y-486650D01*
X403103Y-486343D01*
X403362Y-486113D01*
X403672Y-485960D01*
X404085Y-485845D01*
X404550Y-485807D01*
X405015Y-485845D01*
X405428Y-485960D01*
X405738Y-486113D01*
X405997Y-486343D01*
X406100Y-486650D01*
G01X406992Y-465225D02*
X401928D01*
G01X407050Y-66072D02*
X400525D01*
G01X406978Y263200D02*
X400450D01*
Y253600D01*
X417050D01*
Y263200D01*
G01X400450Y407660D02*
X406954D01*
G01X410526D02*
X417050D01*
Y417260D01*
X400450D01*
Y407660D01*
G01X412693Y-679936D02*
Y-671936D01*
X411493Y-673536D01*
G01Y-679936D02*
X413893D01*
G01X420493D02*
X420693Y-678203D01*
X420993Y-676736D01*
X421393Y-675403D01*
X421893Y-673936D01*
X422693Y-671936D01*
X418693D01*
G01X428693Y-680203D02*
X428493Y-680069D01*
Y-679803D01*
X428693Y-679669D01*
X428893Y-679803D01*
Y-680069D01*
X428693Y-680203D01*
G01X434793Y-673269D02*
X435393Y-672469D01*
X436093Y-672069D01*
X436893Y-671936D01*
X437893Y-672203D01*
X438593Y-672869D01*
X438793Y-673669D01*
X438693Y-674470D01*
X438293Y-675136D01*
X436293Y-676469D01*
X435393Y-677403D01*
X434793Y-678736D01*
X434593Y-679936D01*
X438793D01*
G01X419620Y255383D02*
X419310Y255575D01*
X419103Y255805D01*
X419000Y256073D01*
X419103Y256380D01*
X419310Y256610D01*
X419620Y256840D01*
X420033Y256917D01*
X422100D01*
G01X421583Y258522D02*
X421893Y258752D01*
X422048Y259020D01*
X422100Y259327D01*
X421997Y259710D01*
X421738Y259978D01*
X421428Y260055D01*
X421118Y260017D01*
X420860Y259863D01*
X420343Y259097D01*
X419982Y258752D01*
X419465Y258522D01*
X419000Y258445D01*
Y260055D01*
G01X422100Y262350D02*
X421997Y262043D01*
X421738Y261813D01*
X421428Y261660D01*
X421015Y261545D01*
X420550Y261507D01*
X420085Y261545D01*
X419672Y261660D01*
X419362Y261813D01*
X419103Y262043D01*
X419000Y262350D01*
X419103Y262657D01*
X419362Y262887D01*
X419672Y263040D01*
X420085Y263155D01*
X420550Y263193D01*
X421015Y263155D01*
X421428Y263040D01*
X421738Y262887D01*
X421997Y262657D01*
X422100Y262350D01*
G01X417050Y263200D02*
X410586D01*
G01X419620Y409383D02*
X419310Y409575D01*
X419103Y409805D01*
X419000Y410073D01*
X419103Y410380D01*
X419310Y410610D01*
X419620Y410840D01*
X420033Y410917D01*
X422100D01*
G01X419000Y413250D02*
X422100D01*
X421480Y412790D01*
G01X419000D02*
Y413710D01*
G01Y416273D02*
X419672Y416350D01*
X420240Y416465D01*
X420757Y416618D01*
X421325Y416810D01*
X422100Y417117D01*
Y415583D01*
G01X432493Y-654936D02*
Y-646936D01*
X434493D01*
X435293Y-647336D01*
X435893Y-647869D01*
X436393Y-648669D01*
X436793Y-649603D01*
X436893Y-650936D01*
X436793Y-652269D01*
X436393Y-653203D01*
X435893Y-654003D01*
X435293Y-654536D01*
X434493Y-654936D01*
X432493D01*
G01X436550Y-225000D02*
X436000D01*
Y-215000D01*
G01X446550Y-225000D02*
X445450D01*
G01X453405Y-209550D02*
X451795Y-206450D01*
G01X453405D02*
X451795Y-209550D01*
G01X449500D02*
Y-206450D01*
X449960Y-207070D01*
G01Y-209550D02*
X449040D01*
G01X445940D02*
Y-206450D01*
X447358Y-208672D01*
X445442D01*
G01X436000Y-215000D02*
X438500D01*
G01X443500D02*
X448500D01*
G01X445905Y-146050D02*
X444295Y-142950D01*
G01X445905D02*
X444295Y-146050D01*
G01X442728Y-143467D02*
X442498Y-143157D01*
X442230Y-143002D01*
X441923Y-142950D01*
X441540Y-143053D01*
X441272Y-143312D01*
X441195Y-143622D01*
X441233Y-143932D01*
X441387Y-144190D01*
X442153Y-144707D01*
X442498Y-145068D01*
X442728Y-145585D01*
X442805Y-146050D01*
X441195D01*
G01X438900Y-142950D02*
X439207Y-143053D01*
X439437Y-143312D01*
X439590Y-143622D01*
X439705Y-144035D01*
X439743Y-144500D01*
X439705Y-144965D01*
X439590Y-145378D01*
X439437Y-145688D01*
X439207Y-145947D01*
X438900Y-146050D01*
X438593Y-145947D01*
X438363Y-145688D01*
X438210Y-145378D01*
X438095Y-144965D01*
X438057Y-144500D01*
X438095Y-144035D01*
X438210Y-143622D01*
X438363Y-143312D01*
X438593Y-143053D01*
X438900Y-142950D01*
G01X448500Y-136600D02*
X443500D01*
G01X438500D02*
X436000D01*
Y-126600D01*
X436550D01*
G01Y-117000D02*
X436000D01*
Y-107000D01*
G01X446550Y-117000D02*
X445450D01*
G01Y-126600D02*
X446550D01*
G01X453405Y-101050D02*
X451795Y-97950D01*
G01X453405D02*
X451795Y-101050D01*
G01X449500D02*
Y-97950D01*
X449960Y-98570D01*
G01Y-101050D02*
X449040D01*
G01X447243Y-100430D02*
X447013Y-100792D01*
X446707Y-100998D01*
X446362Y-101050D01*
X446055Y-100998D01*
X445748Y-100740D01*
X445557Y-100430D01*
X445518Y-100120D01*
X445595Y-99758D01*
X445863Y-99500D01*
X446132Y-99397D01*
X446477D01*
G01X446132D02*
X445902Y-99242D01*
X445710Y-98983D01*
X445633Y-98673D01*
X445710Y-98363D01*
X445902Y-98105D01*
X446247Y-97950D01*
X446592Y-98002D01*
X446937Y-98208D01*
G01X436000Y-107000D02*
X438500D01*
G01X443500D02*
X448500D01*
G01X444905Y-27550D02*
X443295Y-24450D01*
G01X444905D02*
X443295Y-27550D01*
G01X441000D02*
Y-24450D01*
X441460Y-25070D01*
G01Y-27550D02*
X440540D01*
G01X438552Y-27188D02*
X438283Y-27447D01*
X437977Y-27550D01*
X437670Y-27447D01*
X437402Y-27137D01*
X437210Y-26672D01*
X437133Y-26207D01*
Y-25638D01*
X437210Y-25173D01*
X437402Y-24760D01*
X437632Y-24553D01*
X437900Y-24450D01*
X438207Y-24553D01*
X438437Y-24760D01*
X438590Y-25070D01*
X438667Y-25483D01*
X438590Y-25845D01*
X438398Y-26207D01*
X438168Y-26413D01*
X437900Y-26465D01*
X437593Y-26362D01*
X437363Y-26103D01*
X437133Y-25638D01*
G01X448500Y-18000D02*
X443500D01*
G01X438500D02*
X436000D01*
Y-8000D01*
X436550D01*
G01X445450D02*
X446550D01*
G01X436550Y220000D02*
X436000D01*
Y230000D01*
G01X446550Y220000D02*
X445450D01*
G01X451855Y236450D02*
X450245Y239550D01*
G01X451855D02*
X450245Y236450D01*
G01X448678Y239033D02*
X448448Y239343D01*
X448180Y239498D01*
X447873Y239550D01*
X447490Y239447D01*
X447222Y239188D01*
X447145Y238878D01*
X447183Y238568D01*
X447337Y238310D01*
X448103Y237793D01*
X448448Y237432D01*
X448678Y236915D01*
X448755Y236450D01*
X447145D01*
G01X436000Y230000D02*
X438500D01*
G01X443500D02*
X448500D01*
G01X445355Y294950D02*
X443745Y298050D01*
G01X445355D02*
X443745Y294950D01*
G01X441450D02*
X441182Y295002D01*
X440875Y295157D01*
X440683Y295415D01*
X440607Y295777D01*
X440683Y296138D01*
X440913Y296448D01*
X441258Y296603D01*
X441642D01*
X441872Y296707D01*
X442063Y296965D01*
X442140Y297327D01*
X442025Y297688D01*
X441757Y297947D01*
X441450Y298050D01*
X441143Y297947D01*
X440875Y297688D01*
X440760Y297327D01*
X440837Y296965D01*
X441028Y296707D01*
X441258Y296603D01*
X441642D01*
X441987Y296448D01*
X442217Y296138D01*
X442293Y295777D01*
X442217Y295415D01*
X442025Y295157D01*
X441718Y295002D01*
X441450Y294950D01*
G01X448500Y304000D02*
X443500D01*
G01X445450Y314000D02*
X446550D01*
G01X438500Y304000D02*
X436000D01*
Y314000D01*
X436550D01*
G01Y326000D02*
X436000D01*
Y336000D01*
G01X446550Y326000D02*
X445450D01*
G01X450355Y341450D02*
X448745Y344550D01*
G01X450355D02*
X448745Y341450D01*
G01X446450D02*
Y344550D01*
X446910Y343930D01*
G01Y341450D02*
X445990D01*
G01X436000Y336000D02*
X438500D01*
G01X443500D02*
X448500D01*
G01X445855Y409950D02*
X444245Y413050D01*
G01X445855D02*
X444245Y409950D01*
G01X442027D02*
X441950Y410622D01*
X441835Y411190D01*
X441682Y411707D01*
X441490Y412275D01*
X441183Y413050D01*
X442717D01*
G01X448500Y420000D02*
X443500D01*
G01X438500D02*
X436000D01*
Y430000D01*
X436550D01*
G01X445450D02*
X446550D01*
G01X453500Y-215000D02*
X456000D01*
Y-225000D01*
X455450D01*
G01X456000Y-136600D02*
X453500D01*
G01X455450Y-126600D02*
X456000D01*
Y-136600D01*
G01X453500Y-107000D02*
X456000D01*
Y-117000D01*
X455450D01*
G01X456000Y-18000D02*
X453500D01*
G01X455450Y-8000D02*
X456000D01*
Y-18000D01*
G01X453500Y230000D02*
X456000D01*
Y220000D01*
X455450D01*
G01X456000Y304000D02*
X453500D01*
G01X455450Y314000D02*
X456000D01*
Y304000D01*
G01X453500Y336000D02*
X456000D01*
Y326000D01*
X455450D01*
G01X456000Y420000D02*
X453500D01*
G01X455450Y430000D02*
X456000D01*
Y420000D01*
M02*
